FILE_TYPE = MACRO_DRAWING;
SET COLOR_WIRE YELLOW;
SET COLOR_PROP ORANGE;
SET COLOR_DOT WHITE;
SET COLOR_ARC YELLOW;
SET COLOR_BODY GREEN;
SET COLOR_NOTE PURPLE;
SET PROP_DISPLAY VALUE;
SET PAGE_NUMBER P131;
FORCEADD OFFPAGE..1
(-2725 -2700);
FORCEPROP 2 LAST $XR1 165 
J 0
(-3127 -2700);
DISPLAY 0.638298 (-3127 -2700);
PAINT MONO (-3127 -2700);
FORCEPROP 2 LAST $XR0 159 
J 0
(-3007 -2700);
DISPLAY 0.638298 (-3007 -2700);
PAINT MONO (-3007 -2700);
FORCEPROP 1 LAST COMMENT_BODY TRUE
J 0
(-2600 -2800);
DISPLAY 0.872340 (-2600 -2800);
PAINT GREEN (-2600 -2800);
DISPLAY INVISIBLE (-2600 -2800);
FORCEPROP 1 LAST OFFPAGE TRUE
J 0
(-2400 -2825);
DISPLAY 0.872340 (-2400 -2825);
PAINT GREEN (-2400 -2825);
DISPLAY INVISIBLE (-2400 -2825);
FORCEPROP 2 LAST CDS_LIB standard
J 0
(-2725 -2700);
PAINT MONO (-2725 -2700);
DISPLAY INVISIBLE (-2725 -2700);
FORCEPROP 2 LAST PATH I1
J 0
(-3000 -2650);
DISPLAY 1.021277 (-3000 -2650);
DISPLAY INVISIBLE (-3000 -2650);
FORCEADD GND..1
(-2975 -1300);
FORCEPROP 3 LASTPIN (-2975 -1250) SIG_NAME GND\g
J 0
(-2965 -1240);
DISPLAY 0.659574 (-2965 -1240);
PAINT MONO (-2965 -1240);
DISPLAY INVISIBLE (-2965 -1240);
FORCEPROP 1 LAST HDL_POWER GND
J 0
(-2975 -1150);
DISPLAY 0.872340 (-2975 -1150);
PAINT GREEN (-2975 -1150);
DISPLAY INVISIBLE (-2975 -1150);
FORCEPROP 2 LAST CDS_LIB logical_power
J 0
(-2975 -1300);
DISPLAY INVISIBLE (-2975 -1300);
FORCEPROP 1 LAST SIZE 1B
J 0
(-2900 -1350);
DISPLAY 0.872340 (-2900 -1350);
PAINT GREEN (-2900 -1350);
DISPLAY INVISIBLE (-2900 -1350);
FORCEPROP 1 LAST PATH I10
J 0
(-2900 -1300);
DISPLAY 0.872340 (-2900 -1300);
PAINT AQUA (-2900 -1300);
DISPLAY INVISIBLE (-2900 -1300);
FORCEADD Q_CAP..1
(3550 400);
FORCEPROP 1 LAST PART_NUMBER CH6223MEA03
J 0
(3600 250);
DISPLAY 0.638298 (3600 250);
DISPLAY INVISIBLE (3600 250);
FORCEPROP 1 LAST VALUE 22UF
J 0
(3600 450);
DISPLAY 0.638298 (3600 450);
FORCEPROP 1 LAST VOLTAGE 16V
J 0
(3600 400);
DISPLAY 0.638298 (3600 400);
FORCEPROP 1 LAST PACK_TYPE C0805
J 0
(3600 300);
DISPLAY 0.638298 (3600 300);
FORCEPROP 1 LAST MATERIAL X6S
J 0
(3600 350);
DISPLAY 0.638298 (3600 350);
FORCEPROP 1 LAST LOCATION PC2141
J 0
(3600 500);
DISPLAY 0.638298 (3600 500);
FORCEPROP 1 LAST TOLERANCE 20%
J 0
(3600 350);
DISPLAY 0.978723 (3600 350);
DISPLAY INVISIBLE (3600 350);
FORCEPROP 2 LAST CDS_LIB pure_quanta
J 0
(3550 400);
DISPLAY INVISIBLE (3550 400);
FORCEPROP 1 LAST PATH I100
J 0
(3600 550);
DISPLAY 0.978723 (3600 550);
PAINT WHITE (3600 550);
DISPLAY INVISIBLE (3600 550);
FORCEPROP 0 LAST $SEC 1
J 0
(3600 550);
DISPLAY INVISIBLE (3600 550);
FORCEPROP 0 LAST CDS_SEC 1
J 0
(3600 550);
DISPLAY INVISIBLE (3600 550);
FORCEPROP 1 LASTPIN (3550 500) $PN 1
J 0
(3560 480);
DISPLAY 0.787234 (3560 480);
PAINT MONO (3560 480);
DISPLAY INVISIBLE (3560 480);
FORCEPROP 1 LASTPIN (3550 300) $PN 2
J 0
(3560 280);
DISPLAY 0.787234 (3560 280);
PAINT MONO (3560 280);
DISPLAY INVISIBLE (3560 280);
FORCEADD GND..1
(3950 100);
FORCEPROP 3 LASTPIN (3950 150) SIG_NAME GND\g
J 0
(3960 160);
DISPLAY 0.659574 (3960 160);
PAINT MONO (3960 160);
DISPLAY INVISIBLE (3960 160);
FORCEPROP 1 LAST HDL_POWER GND
J 0
(3950 250);
DISPLAY 0.872340 (3950 250);
PAINT GREEN (3950 250);
DISPLAY INVISIBLE (3950 250);
FORCEPROP 2 LAST CDS_LIB logical_power
J 0
(3950 100);
DISPLAY INVISIBLE (3950 100);
FORCEPROP 1 LAST SIZE 1B
J 0
(4025 50);
DISPLAY 0.872340 (4025 50);
PAINT GREEN (4025 50);
DISPLAY INVISIBLE (4025 50);
FORCEPROP 1 LAST PATH I101
J 0
(4025 100);
DISPLAY 0.872340 (4025 100);
PAINT AQUA (4025 100);
DISPLAY INVISIBLE (4025 100);
FORCEADD Q_CAP..1
(3950 400);
FORCEPROP 1 LAST PART_NUMBER CH6103KEA03
J 0
(4000 250);
DISPLAY 0.638298 (4000 250);
DISPLAY INVISIBLE (4000 250);
FORCEPROP 1 LAST MATERIAL X6S
J 0
(4000 350);
DISPLAY 0.638298 (4000 350);
FORCEPROP 1 LAST PACK_TYPE C0805
J 0
(4000 300);
DISPLAY 0.638298 (4000 300);
FORCEPROP 1 LAST VOLTAGE 16V
J 0
(4000 400);
DISPLAY 0.638298 (4000 400);
FORCEPROP 1 LAST VALUE 10UF
J 0
(4000 450);
DISPLAY 0.638298 (4000 450);
FORCEPROP 1 LAST LOCATION PC2143
J 0
(4000 500);
DISPLAY 0.680851 (4000 500);
FORCEPROP 1 LAST TOLERANCE 10%
J 0
(3739 360);
DISPLAY 0.787234 (3739 360);
PAINT GREEN (3739 360);
DISPLAY INVISIBLE (3739 360);
FORCEPROP 2 LAST CDS_LIB pure_quanta
J 0
(3950 400);
DISPLAY INVISIBLE (3950 400);
FORCEPROP 1 LAST PATH I102
J 0
(4000 550);
DISPLAY 0.978723 (4000 550);
PAINT WHITE (4000 550);
DISPLAY INVISIBLE (4000 550);
FORCEPROP 0 LAST $SEC 1
J 0
(4000 550);
DISPLAY INVISIBLE (4000 550);
FORCEPROP 0 LAST CDS_SEC 1
J 0
(4000 550);
DISPLAY INVISIBLE (4000 550);
FORCEPROP 1 LASTPIN (3950 500) $PN 1
J 0
(3960 480);
DISPLAY 0.787234 (3960 480);
PAINT MONO (3960 480);
DISPLAY INVISIBLE (3960 480);
FORCEPROP 1 LASTPIN (3950 300) $PN 2
J 0
(3960 280);
DISPLAY 0.787234 (3960 280);
PAINT MONO (3960 280);
DISPLAY INVISIBLE (3960 280);
FORCEADD UNIVERSAL_POWER..1
R 2
(3950 700);
FORCEPROP 3 LASTPIN (3950 650) SIG_NAME P12V_OCP_V3_2\g
J 0
(3960 660);
DISPLAY 0.659574 (3960 660);
PAINT MONO (3960 660);
DISPLAY INVISIBLE (3960 660);
FORCEPROP 1 LAST HDL_POWER P12V_OCP_V3_2
J 1
(3975 750);
DISPLAY 0.723404 (3975 750);
PAINT GREEN (3975 750);
FORCEPROP 2 LAST CDS_LIB logical_power
J 0
(3950 700);
DISPLAY INVISIBLE (3950 700);
FORCEPROP 1 LAST PATH I103
J 2
(3900 725);
DISPLAY 0.872340 (3900 725);
PAINT AQUA (3900 725);
DISPLAY INVISIBLE (3900 725);
FORCEADD GND..1
(3150 1825);
FORCEPROP 3 LASTPIN (3150 1875) SIG_NAME GND\g
J 0
(3160 1885);
DISPLAY 0.659574 (3160 1885);
PAINT MONO (3160 1885);
DISPLAY INVISIBLE (3160 1885);
FORCEPROP 1 LAST HDL_POWER GND
J 0
(3150 1975);
DISPLAY 0.872340 (3150 1975);
PAINT GREEN (3150 1975);
DISPLAY INVISIBLE (3150 1975);
FORCEPROP 1 LAST SIZE 1B
J 0
(3225 1775);
DISPLAY 0.872340 (3225 1775);
PAINT GREEN (3225 1775);
DISPLAY INVISIBLE (3225 1775);
FORCEPROP 2 LAST CDS_LIB logical_power
J 0
(3150 1825);
DISPLAY INVISIBLE (3150 1825);
FORCEPROP 1 LAST PATH I104
J 0
(3225 1825);
DISPLAY 0.872340 (3225 1825);
PAINT AQUA (3225 1825);
DISPLAY INVISIBLE (3225 1825);
FORCEADD Q_CAP..1
(2375 2125);
FORCEPROP 1 LAST PART_NUMBER CH31006KB18
J 0
(2430 2017);
DISPLAY 0.404255 (2430 2017);
DISPLAY INVISIBLE (2430 2017);
FORCEPROP 1 LAST MATERIAL EMPTY
J 0
(2425 1975);
DISPLAY 0.638298 (2425 1975);
PAINT RED (2425 1975);
FORCEPROP 1 LAST VALUE 0.01UF
J 0
(2425 2175);
DISPLAY 0.404255 (2425 2175);
FORCEPROP 1 LAST VOLTAGE 50V
J 0
(2430 2117);
DISPLAY 0.404255 (2430 2117);
FORCEPROP 1 LAST PACK_TYPE C0402
J 0
(2430 2067);
DISPLAY 0.404255 (2430 2067);
FORCEPROP 1 LAST LOCATION PC2149
J 0
(2425 2225);
DISPLAY 0.510638 (2425 2225);
FORCEPROP 1 LASTPIN (2375 2225) $PN 1
J 0
(2385 2205);
DISPLAY 0.787234 (2385 2205);
PAINT MONO (2385 2205);
FORCEPROP 1 LASTPIN (2375 2025) $PN 2
J 0
(2385 2005);
DISPLAY 0.787234 (2385 2005);
PAINT MONO (2385 2005);
FORCEPROP 2 LAST CDS_LIB pure_quanta
J 0
(2375 2125);
DISPLAY INVISIBLE (2375 2125);
FORCEPROP 1 LAST TOLERANCE 10%
J 0
(2425 2075);
DISPLAY 0.638298 (2425 2075);
DISPLAY INVISIBLE (2425 2075);
FORCEPROP 1 LAST PATH I105
J 0
(2425 2275);
DISPLAY 0.978723 (2425 2275);
PAINT WHITE (2425 2275);
DISPLAY INVISIBLE (2425 2275);
FORCEPROP 0 LAST $SEC 1
J 0
(2425 2275);
DISPLAY 0.680851 (2425 2275);
PAINT MONO (2425 2275);
DISPLAY INVISIBLE (2425 2275);
FORCEPROP 0 LAST CDS_SEC 1
J 0
(2425 2275);
DISPLAY 1.021277 (2425 2275);
DISPLAY INVISIBLE (2425 2275);
FORCEADD Q_RES..2
(2650 2150);
FORCEPROP 1 LAST PART_NUMBER CS61002FB02
J 0
(2690 2025);
DISPLAY 0.510638 (2690 2025);
DISPLAY INVISIBLE (2690 2025);
FORCEPROP 1 LAST WATTAGE 1/16W
J 0
(2690 2125);
DISPLAY 0.510638 (2690 2125);
FORCEPROP 1 LAST VALUE 10M
J 0
(2695 2225);
DISPLAY 0.510638 (2695 2225);
FORCEPROP 1 LAST TOLERANCE 1%
J 0
(2695 2175);
DISPLAY 0.510638 (2695 2175);
FORCEPROP 1 LAST MATERIAL CHIP
J 0
(2690 2075);
DISPLAY 0.510638 (2690 2075);
FORCEPROP 1 LAST PACK_TYPE 0402LF
J 0
(2690 1975);
DISPLAY 0.510638 (2690 1975);
FORCEPROP 2 LAST ROOM NIC1_P3V3_BOM1
J 0
(2700 2325);
DISPLAY 0.510638 (2700 2325);
FORCEPROP 1 LAST LOCATION PR4523
J 0
(2695 2275);
DISPLAY 0.978723 (2695 2275);
FORCEPROP 1 LASTPIN (2650 2250) $PN 1
J 0
(2655 2212);
DISPLAY 0.787234 (2655 2212);
PAINT MONO (2655 2212);
FORCEPROP 1 LASTPIN (2650 2050) $PN 2
J 0
(2655 2060);
DISPLAY 0.787234 (2655 2060);
PAINT MONO (2655 2060);
FORCEPROP 1 LAST PATH I106
J 0
(2700 2325);
DISPLAY 0.978723 (2700 2325);
PAINT WHITE (2700 2325);
DISPLAY INVISIBLE (2700 2325);
FORCEPROP 2 LAST CDS_LIB pure_quanta
J 0
(2650 2150);
DISPLAY INVISIBLE (2650 2150);
FORCEPROP 0 LAST $SEC 1
J 0
(2700 2325);
DISPLAY 0.680851 (2700 2325);
PAINT MONO (2700 2325);
DISPLAY INVISIBLE (2700 2325);
FORCEPROP 0 LAST CDS_SEC 1
J 0
(2700 2325);
DISPLAY 1.021277 (2700 2325);
DISPLAY INVISIBLE (2700 2325);
FORCEADD SCHOTTKY_AC..1
R 1
(2775 2750);
FORCEPROP 1 LAST PART_NUMBER BC000340Z30
J 0
(2825 2675);
DISPLAY 0.595745 (2825 2675);
PAINT GREEN (2825 2675);
DISPLAY INVISIBLE (2825 2675);
FORCEPROP 2 LAST VALUE B340A-13-F
J 0
(2825 2725);
DISPLAY 0.638298 (2825 2725);
FORCEPROP 1 LAST LOCATION PD109
J 0
(2825 2775);
DISPLAY 0.723404 (2825 2775);
PAINT GREEN (2825 2775);
FORCEPROP 0 LASTPIN (2775 2625) $PN A
R 1
J 2
(2765 2660);
DISPLAY 0.808511 (2765 2660);
FORCEPROP 0 LASTPIN (2775 2875) $PN C
R 1
J 0
(2765 2835);
DISPLAY 0.808511 (2765 2835);
FORCEPROP 1 LAST MATERIAL IC
J 0
(2825 2650);
DISPLAY 0.723404 (2825 2650);
PAINT GREEN (2825 2650);
DISPLAY INVISIBLE (2825 2650);
FORCEPROP 0 LAST PART_TYPE SMLF
J 0
(2825 2925);
DISPLAY 1.021277 (2825 2925);
DISPLAY INVISIBLE (2825 2925);
FORCEPROP 1 LAST NEEDS_NO_SIZE TRUE
R 1
J 0
(2825 2825);
DISPLAY 0.468085 (2825 2825);
PAINT GREEN (2825 2825);
DISPLAY INVISIBLE (2825 2825);
FORCEPROP 2 LAST CDS_LIB pure_quanta
R 1
J 0
(2775 2750);
DISPLAY INVISIBLE (2775 2750);
FORCEPROP 1 LAST CDS_LMAN_SYM_OUTLINE -75,50,75,-50
R 1
J 0
(2775 2750);
DISPLAY 0.468085 (2775 2750);
PAINT GREEN (2775 2750);
DISPLAY INVISIBLE (2775 2750);
FORCEPROP 1 LAST PATH I107
R 1
J 0
(2775 2750);
DISPLAY 0.723404 (2775 2750);
PAINT GREEN (2775 2750);
DISPLAY INVISIBLE (2775 2750);
FORCEPROP 0 LAST $SEC 1
R 1
J 0
(2825 2825);
DISPLAY INVISIBLE (2825 2825);
FORCEPROP 0 LAST CDS_SEC 1
R 1
J 0
(2825 2825);
DISPLAY INVISIBLE (2825 2825);
FORCEADD Q_RES..2
(3400 2100);
FORCEPROP 1 LAST PART_NUMBER CS41002FB09
J 0
(3440 1975);
DISPLAY 0.510638 (3440 1975);
DISPLAY INVISIBLE (3440 1975);
FORCEPROP 1 LAST PACK_TYPE 0402LF
J 0
(3440 1925);
DISPLAY 0.510638 (3440 1925);
FORCEPROP 1 LAST MATERIAL CHIP
J 0
(3440 2025);
DISPLAY 0.510638 (3440 2025);
FORCEPROP 1 LAST WATTAGE 1/16W
J 0
(3440 2075);
DISPLAY 0.510638 (3440 2075);
FORCEPROP 1 LAST VALUE 100K
J 0
(3445 2175);
DISPLAY 0.510638 (3445 2175);
FORCEPROP 1 LAST TOLERANCE 1%
J 0
(3445 2125);
DISPLAY 0.510638 (3445 2125);
FORCEPROP 2 LAST ROOM NIC1_P3V3_BOM1
J 0
(3450 2275);
DISPLAY 0.319149 (3450 2275);
FORCEPROP 1 LAST LOCATION R3833
J 0
(3445 2225);
DISPLAY 0.638298 (3445 2225);
FORCEPROP 1 LASTPIN (3400 2200) $PN 1
J 0
(3405 2162);
DISPLAY 0.787234 (3405 2162);
PAINT MONO (3405 2162);
FORCEPROP 1 LASTPIN (3400 2000) $PN 2
J 0
(3405 2010);
DISPLAY 0.787234 (3405 2010);
PAINT MONO (3405 2010);
FORCEPROP 1 LAST PATH I108
J 0
(3450 2275);
DISPLAY 0.978723 (3450 2275);
PAINT WHITE (3450 2275);
DISPLAY INVISIBLE (3450 2275);
FORCEPROP 2 LAST CDS_LIB pure_quanta
J 0
(3400 2100);
DISPLAY INVISIBLE (3400 2100);
FORCEPROP 0 LAST $SEC 1
J 0
(3450 2275);
DISPLAY 0.680851 (3450 2275);
PAINT MONO (3450 2275);
DISPLAY INVISIBLE (3450 2275);
FORCEPROP 0 LAST CDS_SEC 1
J 0
(3450 2275);
DISPLAY 1.021277 (3450 2275);
DISPLAY INVISIBLE (3450 2275);
FORCEADD Q_CAP..1
(3275 2725);
FORCEPROP 1 LAST PART_NUMBER CH4104K1B00
J 0
(3325 2575);
DISPLAY 0.638298 (3325 2575);
DISPLAY INVISIBLE (3325 2575);
FORCEPROP 1 LAST VOLTAGE 25V
J 0
(3325 2725);
DISPLAY 0.638298 (3325 2725);
FORCEPROP 1 LAST VALUE 0.1UF
J 0
(3325 2775);
DISPLAY 0.638298 (3325 2775);
FORCEPROP 1 LAST MATERIAL X7R
J 0
(3325 2675);
DISPLAY 0.638298 (3325 2675);
FORCEPROP 1 LAST PACK_TYPE 0402
J 0
(3325 2625);
DISPLAY 0.638298 (3325 2625);
FORCEPROP 1 LAST LOCATION PC2137
J 0
(3325 2825);
DISPLAY 0.638298 (3325 2825);
FORCEPROP 1 LASTPIN (3275 2825) $PN 1
J 0
(3285 2805);
DISPLAY 0.787234 (3285 2805);
PAINT MONO (3285 2805);
FORCEPROP 1 LASTPIN (3275 2625) $PN 2
J 0
(3285 2605);
DISPLAY 0.787234 (3285 2605);
PAINT MONO (3285 2605);
FORCEPROP 2 LAST CDS_LIB pure_quanta
J 0
(3275 2725);
DISPLAY INVISIBLE (3275 2725);
FORCEPROP 1 LAST TOLERANCE 10%
J 0
(3325 2675);
DISPLAY 0.978723 (3325 2675);
DISPLAY INVISIBLE (3325 2675);
FORCEPROP 1 LAST PATH I109
J 0
(3325 2875);
DISPLAY 0.978723 (3325 2875);
PAINT WHITE (3325 2875);
DISPLAY INVISIBLE (3325 2875);
FORCEPROP 0 LAST $SEC 1
J 0
(3325 2875);
DISPLAY 0.680851 (3325 2875);
PAINT MONO (3325 2875);
DISPLAY INVISIBLE (3325 2875);
FORCEPROP 0 LAST CDS_SEC 1
J 0
(3325 2875);
DISPLAY 1.021277 (3325 2875);
DISPLAY INVISIBLE (3325 2875);
FORCEADD Q_RES..2
(-2550 -1450);
FORCEPROP 1 LAST PART_NUMBER CS21002FB06
J 0
(-2510 -1575);
DISPLAY 0.638298 (-2510 -1575);
DISPLAY INVISIBLE (-2510 -1575);
FORCEPROP 1 LAST VALUE 1K
J 0
(-2505 -1375);
DISPLAY 0.638298 (-2505 -1375);
FORCEPROP 1 LAST WATTAGE 1/16W
J 0
(-2510 -1475);
DISPLAY 0.638298 (-2510 -1475);
FORCEPROP 1 LAST TOLERANCE 1%
J 0
(-2505 -1425);
DISPLAY 0.638298 (-2505 -1425);
FORCEPROP 1 LAST MATERIAL CHIP
J 0
(-2510 -1525);
DISPLAY 0.638298 (-2510 -1525);
FORCEPROP 1 LAST PACK_TYPE 0402LF
J 0
(-2510 -1575);
DISPLAY 0.638298 (-2510 -1575);
FORCEPROP 1 LAST LOCATION R3133
J 0
(-2505 -1325);
DISPLAY 0.978723 (-2505 -1325);
FORCEPROP 1 LASTPIN (-2550 -1350) $PN 1
J 0
(-2545 -1388);
DISPLAY 0.787234 (-2545 -1388);
PAINT MONO (-2545 -1388);
FORCEPROP 1 LASTPIN (-2550 -1550) $PN 2
J 0
(-2545 -1540);
DISPLAY 0.787234 (-2545 -1540);
PAINT MONO (-2545 -1540);
FORCEPROP 2 LAST CDS_LIB pure_quanta
J 0
(-2550 -1450);
DISPLAY INVISIBLE (-2550 -1450);
FORCEPROP 1 LAST PATH I11
J 0
(-2500 -1275);
DISPLAY 0.978723 (-2500 -1275);
PAINT WHITE (-2500 -1275);
DISPLAY INVISIBLE (-2500 -1275);
FORCEPROP 0 LAST $SEC 1
J 0
(-2500 -1275);
DISPLAY 0.680851 (-2500 -1275);
PAINT MONO (-2500 -1275);
DISPLAY INVISIBLE (-2500 -1275);
FORCEPROP 0 LAST CDS_SEC 1
J 0
(-2500 -1275);
DISPLAY 1.021277 (-2500 -1275);
DISPLAY INVISIBLE (-2500 -1275);
FORCEADD Q_RES..2
(3800 2100);
FORCEPROP 1 LAST PART_NUMBER CS41002FB09
J 0
(3840 1975);
DISPLAY 0.510638 (3840 1975);
DISPLAY INVISIBLE (3840 1975);
FORCEPROP 1 LAST WATTAGE 1/16W
J 0
(3840 2075);
DISPLAY 0.510638 (3840 2075);
FORCEPROP 1 LAST MATERIAL CHIP
J 0
(3840 2025);
DISPLAY 0.510638 (3840 2025);
FORCEPROP 1 LAST PACK_TYPE 0402LF
J 0
(3840 1925);
DISPLAY 0.510638 (3840 1925);
FORCEPROP 1 LAST TOLERANCE 1%
J 0
(3845 2125);
DISPLAY 0.510638 (3845 2125);
FORCEPROP 1 LAST VALUE 100K
J 0
(3845 2175);
DISPLAY 0.510638 (3845 2175);
FORCEPROP 2 LAST ROOM NIC1_P3V3_BOM1
J 0
(3850 2275);
DISPLAY 0.510638 (3850 2275);
FORCEPROP 1 LAST LOCATION R3826
J 0
(3845 2225);
DISPLAY 0.638298 (3845 2225);
FORCEPROP 1 LASTPIN (3800 2200) $PN 1
J 0
(3805 2162);
DISPLAY 0.787234 (3805 2162);
PAINT MONO (3805 2162);
FORCEPROP 1 LASTPIN (3800 2000) $PN 2
J 0
(3805 2010);
DISPLAY 0.787234 (3805 2010);
PAINT MONO (3805 2010);
FORCEPROP 1 LAST PATH I110
J 0
(3850 2275);
DISPLAY 0.978723 (3850 2275);
PAINT WHITE (3850 2275);
DISPLAY INVISIBLE (3850 2275);
FORCEPROP 2 LAST CDS_LIB pure_quanta
J 0
(3800 2100);
DISPLAY INVISIBLE (3800 2100);
FORCEPROP 0 LAST $SEC 1
J 0
(3850 2275);
DISPLAY 0.680851 (3850 2275);
PAINT MONO (3850 2275);
DISPLAY INVISIBLE (3850 2275);
FORCEPROP 0 LAST CDS_SEC 1
J 0
(3850 2275);
DISPLAY 1.021277 (3850 2275);
DISPLAY INVISIBLE (3850 2275);
FORCEADD VCCAUX15..1
(3600 2425);
FORCEPROP 3 LASTPIN (3600 2375) SIG_NAME P3V3_AUX\g
J 0
(3610 2385);
DISPLAY 0.659574 (3610 2385);
PAINT MONO (3610 2385);
DISPLAY INVISIBLE (3610 2385);
FORCEPROP 1 LAST HDL_POWER P3V3_AUX
J 1
(3600 2475);
DISPLAY 0.723404 (3600 2475);
PAINT GREEN (3600 2475);
FORCEPROP 2 LAST CDS_LIB logical_power
J 0
(3600 2425);
DISPLAY INVISIBLE (3600 2425);
FORCEPROP 1 LAST PATH I111
J 0
(3650 2450);
DISPLAY 0.872340 (3650 2450);
PAINT AQUA (3650 2450);
DISPLAY INVISIBLE (3650 2450);
FORCEADD GND..1
(3850 2425);
FORCEPROP 3 LASTPIN (3850 2475) SIG_NAME GND\g
J 0
(3860 2485);
DISPLAY 0.659574 (3860 2485);
PAINT MONO (3860 2485);
DISPLAY INVISIBLE (3860 2485);
FORCEPROP 1 LAST HDL_POWER GND
J 0
(3850 2575);
DISPLAY 0.872340 (3850 2575);
PAINT GREEN (3850 2575);
DISPLAY INVISIBLE (3850 2575);
FORCEPROP 2 LAST CDS_LIB logical_power
J 0
(3850 2425);
DISPLAY INVISIBLE (3850 2425);
FORCEPROP 1 LAST SIZE 1B
J 0
(3925 2375);
DISPLAY 0.872340 (3925 2375);
PAINT GREEN (3925 2375);
DISPLAY INVISIBLE (3925 2375);
FORCEPROP 1 LAST PATH I112
J 0
(3925 2425);
DISPLAY 0.872340 (3925 2425);
PAINT AQUA (3925 2425);
DISPLAY INVISIBLE (3925 2425);
FORCEADD Q_CAP..1
(3850 2725);
FORCEPROP 1 LAST PART_NUMBER CH6103KEA01
J 0
(3900 2575);
DISPLAY 0.638298 (3900 2575);
DISPLAY INVISIBLE (3900 2575);
FORCEPROP 1 LAST VOLTAGE 16V
J 0
(3900 2725);
DISPLAY 0.638298 (3900 2725);
FORCEPROP 1 LAST PACK_TYPE C0805
J 0
(3900 2625);
DISPLAY 0.638298 (3900 2625);
FORCEPROP 1 LAST VALUE 10UF
J 0
(3900 2775);
DISPLAY 0.638298 (3900 2775);
FORCEPROP 1 LAST MATERIAL X6S
J 0
(3900 2675);
DISPLAY 0.638298 (3900 2675);
FORCEPROP 1 LAST LOCATION PC2142
J 0
(3900 2825);
DISPLAY 0.680851 (3900 2825);
FORCEPROP 1 LAST TOLERANCE 10%
J 0
(3639 2685);
DISPLAY 0.787234 (3639 2685);
PAINT GREEN (3639 2685);
DISPLAY INVISIBLE (3639 2685);
FORCEPROP 2 LAST CDS_LIB pure_quanta
J 0
(3850 2725);
DISPLAY INVISIBLE (3850 2725);
FORCEPROP 1 LAST PATH I113
J 0
(3900 2875);
DISPLAY 0.978723 (3900 2875);
PAINT WHITE (3900 2875);
DISPLAY INVISIBLE (3900 2875);
FORCEPROP 0 LAST $SEC 1
J 0
(3900 2875);
DISPLAY INVISIBLE (3900 2875);
FORCEPROP 0 LAST CDS_SEC 1
J 0
(3900 2875);
DISPLAY INVISIBLE (3900 2875);
FORCEPROP 1 LASTPIN (3850 2825) $PN 1
J 0
(3860 2805);
DISPLAY 0.787234 (3860 2805);
PAINT MONO (3860 2805);
DISPLAY INVISIBLE (3860 2805);
FORCEPROP 1 LASTPIN (3850 2625) $PN 2
J 0
(3860 2605);
DISPLAY 0.787234 (3860 2605);
PAINT MONO (3860 2605);
DISPLAY INVISIBLE (3860 2605);
FORCEADD UNIVERSAL_POWER..1
R 2
(3850 3025);
FORCEPROP 3 LASTPIN (3850 2975) SIG_NAME P3V3_OCP_V3_2_R\g
J 0
(3860 2985);
DISPLAY 0.659574 (3860 2985);
PAINT MONO (3860 2985);
DISPLAY INVISIBLE (3860 2985);
FORCEPROP 1 LAST HDL_POWER P3V3_OCP_V3_2_R
J 1
(3850 3075);
DISPLAY 0.723404 (3850 3075);
PAINT GREEN (3850 3075);
FORCEPROP 2 LAST CDS_LIB logical_power
J 0
(3850 3025);
DISPLAY INVISIBLE (3850 3025);
FORCEPROP 1 LAST PATH I114
J 2
(3800 3050);
DISPLAY 0.872340 (3800 3050);
PAINT AQUA (3800 3050);
DISPLAY INVISIBLE (3800 3050);
FORCEADD OFFPAGE..2
(4200 1800);
PAINT AQUA (4200 1800);
FORCEPROP 2 LAST $XR0 164 
J 0
(4389 1800);
DISPLAY 0.638298 (4389 1800);
PAINT MONO (4389 1800);
FORCEPROP 1 LAST COMMENT_BODY TRUE
J 0
(4155 1705);
DISPLAY 0.872340 (4155 1705);
PAINT GREEN (4155 1705);
DISPLAY INVISIBLE (4155 1705);
FORCEPROP 1 LAST OFFPAGE TRUE
J 0
(4525 1675);
DISPLAY 0.872340 (4525 1675);
PAINT AQUA (4525 1675);
DISPLAY INVISIBLE (4525 1675);
FORCEPROP 2 LAST CDS_LIB standard
J 0
(4200 1800);
DISPLAY INVISIBLE (4200 1800);
FORCEPROP 2 LAST PATH I115
J 0
(4400 1850);
DISPLAY 1.021277 (4400 1850);
DISPLAY INVISIBLE (4400 1850);
FORCEADD UNIVERSAL_POWER..1
(-2550 -1150);
FORCEPROP 3 LASTPIN (-2550 -1200) SIG_NAME P3V3_AUX\g
J 0
(-2540 -1190);
DISPLAY 0.659574 (-2540 -1190);
PAINT MONO (-2540 -1190);
DISPLAY INVISIBLE (-2540 -1190);
FORCEPROP 1 LAST HDL_POWER P3V3_AUX
J 1
(-2550 -1100);
DISPLAY 0.872340 (-2550 -1100);
PAINT GREEN (-2550 -1100);
FORCEPROP 2 LAST CDS_LIB logical_power
J 0
(-2550 -1150);
DISPLAY INVISIBLE (-2550 -1150);
FORCEPROP 1 LAST PATH I12
J 0
(-2500 -1125);
DISPLAY 0.872340 (-2500 -1125);
PAINT AQUA (-2500 -1125);
DISPLAY INVISIBLE (-2500 -1125);
FORCEADD Q_RES..2
(-2325 -1450);
FORCEPROP 1 LAST PART_NUMBER CS21002FB06
J 0
(-2285 -1575);
DISPLAY 0.638298 (-2285 -1575);
DISPLAY INVISIBLE (-2285 -1575);
FORCEPROP 1 LAST WATTAGE 1/16W
J 0
(-2285 -1475);
DISPLAY 0.638298 (-2285 -1475);
FORCEPROP 1 LAST TOLERANCE 1%
J 0
(-2280 -1425);
DISPLAY 0.638298 (-2280 -1425);
FORCEPROP 1 LAST VALUE 1K
J 0
(-2280 -1375);
DISPLAY 0.638298 (-2280 -1375);
FORCEPROP 1 LAST MATERIAL CHIP
J 0
(-2285 -1525);
DISPLAY 0.638298 (-2285 -1525);
FORCEPROP 1 LAST PACK_TYPE 0402LF
J 0
(-2285 -1575);
DISPLAY 0.638298 (-2285 -1575);
FORCEPROP 1 LAST LOCATION R3135
J 0
(-2280 -1325);
DISPLAY 0.978723 (-2280 -1325);
FORCEPROP 1 LASTPIN (-2325 -1350) $PN 1
J 0
(-2320 -1388);
DISPLAY 0.787234 (-2320 -1388);
PAINT MONO (-2320 -1388);
FORCEPROP 1 LASTPIN (-2325 -1550) $PN 2
J 0
(-2320 -1540);
DISPLAY 0.787234 (-2320 -1540);
PAINT MONO (-2320 -1540);
FORCEPROP 2 LAST CDS_LIB pure_quanta
J 0
(-2325 -1450);
DISPLAY INVISIBLE (-2325 -1450);
FORCEPROP 1 LAST PATH I13
J 0
(-2275 -1275);
DISPLAY 0.978723 (-2275 -1275);
PAINT WHITE (-2275 -1275);
DISPLAY INVISIBLE (-2275 -1275);
FORCEPROP 0 LAST $SEC 1
J 0
(-2275 -1275);
DISPLAY 0.680851 (-2275 -1275);
PAINT MONO (-2275 -1275);
DISPLAY INVISIBLE (-2275 -1275);
FORCEPROP 0 LAST CDS_SEC 1
J 0
(-2275 -1275);
DISPLAY 1.021277 (-2275 -1275);
DISPLAY INVISIBLE (-2275 -1275);
FORCEADD Q_RES..2
(-2975 -350);
FORCEPROP 1 LAST PART_NUMBER CS31002FB08
J 0
(-2945 -433);
DISPLAY 0.638298 (-2945 -433);
DISPLAY INVISIBLE (-2945 -433);
FORCEPROP 1 LAST PACK_TYPE 0402LF
J 0
(-2945 -483);
DISPLAY 0.638298 (-2945 -483);
FORCEPROP 1 LAST VALUE 10K
J 0
(-2940 -233);
DISPLAY 0.638298 (-2940 -233);
FORCEPROP 1 LAST TOLERANCE 1%
J 0
(-2940 -283);
DISPLAY 0.638298 (-2940 -283);
FORCEPROP 1 LAST MATERIAL EMPTY
J 0
(-2945 -383);
DISPLAY 0.638298 (-2945 -383);
PAINT RED (-2945 -383);
FORCEPROP 1 LAST WATTAGE 1/16W
J 0
(-2945 -333);
DISPLAY 0.638298 (-2945 -333);
FORCEPROP 2 LAST ROOM NIC1_P12V_MAM_MAM_BOM1
J 0
(-2925 -150);
DISPLAY 1.021277 (-2925 -150);
FORCEPROP 1 LAST $LOCATION R4065
J 0
(-2940 -183);
DISPLAY 0.638298 (-2940 -183);
FORCEPROP 1 LASTPIN (-2975 -250) $PN 1
J 0
(-2970 -288);
DISPLAY 0.787234 (-2970 -288);
PAINT MONO (-2970 -288);
FORCEPROP 1 LASTPIN (-2975 -450) $PN 2
J 0
(-2970 -440);
DISPLAY 0.787234 (-2970 -440);
PAINT MONO (-2970 -440);
FORCEPROP 1 LAST PATH I14
J 0
(-2925 -175);
DISPLAY 0.978723 (-2925 -175);
PAINT WHITE (-2925 -175);
DISPLAY INVISIBLE (-2925 -175);
FORCEPROP 2 LAST CDS_LIB pure_quanta
J 0
(-2975 -350);
DISPLAY INVISIBLE (-2975 -350);
FORCEPROP 2 LAST ROOM1 NIC1_P12V_MAM_TIC_BOM2
J 0
(-2925 -100);
DISPLAY 1.021277 (-2925 -100);
DISPLAY INVISIBLE (-2925 -100);
FORCEPROP 0 LAST CDS_LOCATION R4065
J 0
(-2925 -150);
DISPLAY 1.021277 (-2925 -150);
DISPLAY INVISIBLE (-2925 -150);
FORCEPROP 0 LAST $SEC 1
J 0
(-2925 -150);
DISPLAY 0.680851 (-2925 -150);
PAINT MONO (-2925 -150);
DISPLAY INVISIBLE (-2925 -150);
FORCEPROP 0 LAST CDS_SEC 1
J 0
(-2925 -150);
DISPLAY 1.021277 (-2925 -150);
DISPLAY INVISIBLE (-2925 -150);
FORCEADD UNIVERSAL_POWER..1
(-2975 -100);
FORCEPROP 3 LASTPIN (-2975 -150) SIG_NAME P12V_AUX\g
J 0
(-2965 -140);
DISPLAY 0.659574 (-2965 -140);
PAINT MONO (-2965 -140);
DISPLAY INVISIBLE (-2965 -140);
FORCEPROP 1 LAST HDL_POWER P12V_AUX
J 1
(-2975 -50);
DISPLAY 0.872340 (-2975 -50);
PAINT GREEN (-2975 -50);
FORCEPROP 2 LAST CDS_LIB logical_power
J 0
(-2975 -100);
DISPLAY INVISIBLE (-2975 -100);
FORCEPROP 1 LAST PATH I15
J 0
(-2925 -75);
DISPLAY 0.872340 (-2925 -75);
PAINT AQUA (-2925 -75);
DISPLAY INVISIBLE (-2925 -75);
FORCEADD MOSFET_NCH_DUAL..2
(-2350 -625);
FORCEPROP 1 LAST PART_NUMBER BAM138K0003
J 0
(-2199 -719);
DISPLAY 0.723404 (-2199 -719);
PAINT GREEN (-2199 -719);
DISPLAY INVISIBLE (-2199 -719);
FORCEPROP 1 LAST MATERIAL EMPTY
J 0
(-2199 -774);
DISPLAY 0.723404 (-2199 -774);
PAINT RED (-2199 -774);
FORCEPROP 2 LAST VALUE PJT138K
J 0
(-2175 -600);
DISPLAY 1.021277 (-2175 -600);
FORCEPROP 2 LAST PART_TYPE SMLF
J 0
(-2175 -550);
DISPLAY 1.021277 (-2175 -550);
FORCEPROP 2 LAST ROOM NIC1_P12V_MAM_MAM_BOM1
J 0
(-2175 -500);
DISPLAY 1.021277 (-2175 -500);
FORCEPROP 1 LAST $LOCATION Q118
J 0
(-2199 -649);
DISPLAY 0.723404 (-2199 -649);
PAINT GREEN (-2199 -649);
FORCEPROP 0 LASTPIN (-2300 -425) $PN 3
R 1
J 0
(-2310 -415);
DISPLAY 0.680851 (-2310 -415);
PAINT MONO (-2310 -415);
FORCEPROP 0 LASTPIN (-2550 -675) $PN 5
J 2
(-2560 -665);
DISPLAY 0.680851 (-2560 -665);
PAINT MONO (-2560 -665);
FORCEPROP 0 LASTPIN (-2300 -825) $PN 4
R 1
J 2
(-2310 -835);
DISPLAY 0.680851 (-2310 -835);
PAINT MONO (-2310 -835);
FORCEPROP 1 LAST PATH I16
J 0
(-2200 -775);
DISPLAY 0.723404 (-2200 -775);
PAINT GREEN (-2200 -775);
DISPLAY INVISIBLE (-2200 -775);
FORCEPROP 2 LAST CDS_LIB pure_quanta
J 0
(-2350 -625);
DISPLAY INVISIBLE (-2350 -625);
FORCEPROP 1 LAST CDS_LMAN_SYM_OUTLINE -150,150,150,-150
J 0
(-2350 -625);
DISPLAY 0.468085 (-2350 -625);
PAINT GREEN (-2350 -625);
DISPLAY INVISIBLE (-2350 -625);
FORCEPROP 1 LAST NEEDS_NO_SIZE TRUE
J 0
(-2200 -734);
DISPLAY 0.468085 (-2200 -734);
PAINT GREEN (-2200 -734);
DISPLAY INVISIBLE (-2200 -734);
FORCEPROP 2 LAST ROOM1 NIC1_P12V_MAM_TIC_BOM2
J 0
(-2175 -450);
DISPLAY 1.021277 (-2175 -450);
DISPLAY INVISIBLE (-2175 -450);
FORCEPROP 0 LAST CDS_LOCATION Q118
J 0
(-2175 -500);
DISPLAY 1.021277 (-2175 -500);
DISPLAY INVISIBLE (-2175 -500);
FORCEPROP 0 LAST $SEC 2
J 0
(-2175 -500);
DISPLAY 0.680851 (-2175 -500);
PAINT MONO (-2175 -500);
DISPLAY INVISIBLE (-2175 -500);
FORCEPROP 0 LAST CDS_SEC 2
J 0
(-2175 -500);
DISPLAY 1.021277 (-2175 -500);
DISPLAY INVISIBLE (-2175 -500);
FORCEADD GND..1
(-2300 -925);
FORCEPROP 3 LASTPIN (-2300 -875) SIG_NAME GND\g
J 0
(-2290 -865);
DISPLAY 0.659574 (-2290 -865);
PAINT MONO (-2290 -865);
DISPLAY INVISIBLE (-2290 -865);
FORCEPROP 1 LAST HDL_POWER GND
J 0
(-2300 -775);
DISPLAY 0.872340 (-2300 -775);
PAINT GREEN (-2300 -775);
DISPLAY INVISIBLE (-2300 -775);
FORCEPROP 1 LAST SIZE 1B
J 0
(-2225 -975);
DISPLAY 0.872340 (-2225 -975);
PAINT GREEN (-2225 -975);
DISPLAY INVISIBLE (-2225 -975);
FORCEPROP 2 LAST CDS_LIB logical_power
J 0
(-2300 -925);
DISPLAY INVISIBLE (-2300 -925);
FORCEPROP 1 LAST PATH I17
J 0
(-2225 -925);
DISPLAY 0.872340 (-2225 -925);
PAINT AQUA (-2225 -925);
DISPLAY INVISIBLE (-2225 -925);
FORCEADD UNIVERSAL_GND..1
(-1575 -2950);
FORCEPROP 3 LASTPIN (-1575 -2900) SIG_NAME GND\g
J 0
(-1565 -2890);
DISPLAY 0.659574 (-1565 -2890);
PAINT MONO (-1565 -2890);
DISPLAY INVISIBLE (-1565 -2890);
FORCEPROP 1 LAST HDL_POWER GND
J 1
(-1550 -3025);
DISPLAY 0.872340 (-1550 -3025);
PAINT GREEN (-1550 -3025);
DISPLAY INVISIBLE (-1550 -3025);
FORCEPROP 2 LAST CDS_LIB logical_power
J 0
(-1575 -2950);
PAINT MONO (-1575 -2950);
DISPLAY INVISIBLE (-1575 -2950);
FORCEPROP 1 LAST PATH I18
J 0
(-1500 -2950);
DISPLAY 0.872340 (-1500 -2950);
PAINT AQUA (-1500 -2950);
DISPLAY INVISIBLE (-1500 -2950);
FORCEADD 74LVC2G07DW7..1
(-1175 -2650);
FORCEPROP 1 LAST PART_NUMBER AL002G07003
J 0
(-1344 -2416);
DISPLAY 0.723404 (-1344 -2416);
PAINT GREEN (-1344 -2416);
DISPLAY INVISIBLE (-1344 -2416);
FORCEPROP 2 LAST VALUE 74LVC2G07DW-7
J 0
(-1325 -2225);
DISPLAY 1.021277 (-1325 -2225);
FORCEPROP 2 LAST PART_TYPE SMLF
J 0
(-1325 -2175);
DISPLAY 1.021277 (-1325 -2175);
FORCEPROP 1 LAST MATERIAL IC
J 0
(-1344 -2543);
DISPLAY 0.723404 (-1344 -2543);
PAINT GREEN (-1344 -2543);
FORCEPROP 1 LAST LOCATION U59
J 0
(-1344 -2269);
DISPLAY 0.723404 (-1344 -2269);
PAINT GREEN (-1344 -2269);
FORCEPROP 0 LASTPIN (-1500 -2600) $PN 1
J 2
(-1510 -2590);
DISPLAY 0.680851 (-1510 -2590);
PAINT MONO (-1510 -2590);
FORCEPROP 0 LASTPIN (-850 -2600) $PN 6
J 0
(-840 -2590);
DISPLAY 0.680851 (-840 -2590);
PAINT MONO (-840 -2590);
FORCEPROP 0 LASTPIN (-1500 -2700) $PN 3
J 2
(-1510 -2690);
DISPLAY 0.680851 (-1510 -2690);
PAINT MONO (-1510 -2690);
FORCEPROP 0 LASTPIN (-850 -2700) $PN 4
J 0
(-840 -2690);
DISPLAY 0.680851 (-840 -2690);
PAINT MONO (-840 -2690);
FORCEPROP 0 LASTPIN (-1500 -2650) $PN 2
J 2
(-1510 -2640);
DISPLAY 0.680851 (-1510 -2640);
PAINT MONO (-1510 -2640);
FORCEPROP 0 LASTPIN (-850 -2650) $PN 5
J 0
(-840 -2640);
DISPLAY 0.680851 (-840 -2640);
PAINT MONO (-840 -2640);
FORCEPROP 1 LAST NEEDS_NO_SIZE TRUE
J 0
(-1175 -2650);
DISPLAY 0.723404 (-1175 -2650);
PAINT GREEN (-1175 -2650);
DISPLAY INVISIBLE (-1175 -2650);
FORCEPROP 1 LAST CDS_LMAN_SYM_OUTLINE -175,100,175,-100
J 0
(-1175 -2650);
DISPLAY 0.468085 (-1175 -2650);
PAINT GREEN (-1175 -2650);
DISPLAY INVISIBLE (-1175 -2650);
FORCEPROP 2 LAST CDS_LIB pure_quanta
J 0
(-1175 -2650);
DISPLAY INVISIBLE (-1175 -2650);
FORCEPROP 1 LAST PATH I19
J 0
(-1175 -2650);
DISPLAY 0.723404 (-1175 -2650);
PAINT GREEN (-1175 -2650);
DISPLAY INVISIBLE (-1175 -2650);
FORCEPROP 0 LAST $SEC 1
J 0
(-1325 -2125);
DISPLAY 0.680851 (-1325 -2125);
PAINT MONO (-1325 -2125);
DISPLAY INVISIBLE (-1325 -2125);
FORCEPROP 0 LAST CDS_SEC 1
J 0
(-1325 -2125);
DISPLAY 1.021277 (-1325 -2125);
DISPLAY INVISIBLE (-1325 -2125);
FORCEADD OFFPAGE..1
(-2725 -2600);
FORCEPROP 2 LAST $XR1 165 
J 0
(-3127 -2600);
DISPLAY 0.638298 (-3127 -2600);
PAINT MONO (-3127 -2600);
FORCEPROP 2 LAST $XR0 159 
J 0
(-3007 -2600);
DISPLAY 0.638298 (-3007 -2600);
PAINT MONO (-3007 -2600);
FORCEPROP 1 LAST COMMENT_BODY TRUE
J 0
(-2600 -2700);
DISPLAY 0.872340 (-2600 -2700);
PAINT GREEN (-2600 -2700);
DISPLAY INVISIBLE (-2600 -2700);
FORCEPROP 1 LAST OFFPAGE TRUE
J 0
(-2400 -2725);
DISPLAY 0.872340 (-2400 -2725);
PAINT GREEN (-2400 -2725);
DISPLAY INVISIBLE (-2400 -2725);
FORCEPROP 2 LAST CDS_LIB standard
J 0
(-2725 -2600);
PAINT MONO (-2725 -2600);
DISPLAY INVISIBLE (-2725 -2600);
FORCEPROP 2 LAST PATH I2
J 0
(-3000 -2550);
DISPLAY 1.021277 (-3000 -2550);
DISPLAY INVISIBLE (-3000 -2550);
FORCEADD UNIVERSAL_GND..1
(-500 -3025);
FORCEPROP 3 LASTPIN (-500 -2975) SIG_NAME GND\g
J 0
(-490 -2965);
DISPLAY 0.659574 (-490 -2965);
PAINT MONO (-490 -2965);
DISPLAY INVISIBLE (-490 -2965);
FORCEPROP 1 LAST HDL_POWER GND
J 1
(-475 -3100);
DISPLAY 0.872340 (-475 -3100);
PAINT GREEN (-475 -3100);
DISPLAY INVISIBLE (-475 -3100);
FORCEPROP 2 LAST CDS_LIB logical_power
J 0
(-500 -3025);
PAINT MONO (-500 -3025);
DISPLAY INVISIBLE (-500 -3025);
FORCEPROP 1 LAST PATH I20
J 0
(-425 -3025);
DISPLAY 0.872340 (-425 -3025);
PAINT AQUA (-425 -3025);
DISPLAY INVISIBLE (-425 -3025);
FORCEADD Q_CAP..1
(-500 -2825);
FORCEPROP 1 LAST PART_NUMBER CH4104K1B00
J 0
(-450 -2975);
DISPLAY 0.510638 (-450 -2975);
DISPLAY INVISIBLE (-450 -2975);
FORCEPROP 1 LAST TOLERANCE 10%
J 0
(-450 -2875);
DISPLAY 0.510638 (-450 -2875);
FORCEPROP 1 LAST VALUE 0.1UF
J 0
(-450 -2775);
DISPLAY 0.510638 (-450 -2775);
FORCEPROP 1 LAST VOLTAGE 25V
J 0
(-450 -2825);
DISPLAY 0.510638 (-450 -2825);
FORCEPROP 1 LAST PACK_TYPE 0402
J 0
(-450 -3025);
DISPLAY 0.510638 (-450 -3025);
FORCEPROP 1 LAST MATERIAL X7R
J 0
(-450 -2925);
DISPLAY 0.510638 (-450 -2925);
FORCEPROP 1 LAST $LOCATION C1810
J 0
(-450 -2725);
DISPLAY 0.978723 (-450 -2725);
FORCEPROP 1 LASTPIN (-500 -2725) $PN 1
J 0
(-490 -2745);
DISPLAY 0.787234 (-490 -2745);
FORCEPROP 1 LASTPIN (-500 -2925) $PN 2
J 0
(-490 -2945);
DISPLAY 0.787234 (-490 -2945);
FORCEPROP 2 LAST CDS_LIB pure_quanta
J 0
(-500 -2825);
PAINT MONO (-500 -2825);
DISPLAY INVISIBLE (-500 -2825);
FORCEPROP 1 LAST PATH I21
J 0
(-450 -2675);
DISPLAY 0.978723 (-450 -2675);
PAINT WHITE (-450 -2675);
DISPLAY INVISIBLE (-450 -2675);
FORCEPROP 2 LAST CDS_LOCATION C1810
J 0
(-450 -2625);
DISPLAY 1.021277 (-450 -2625);
DISPLAY INVISIBLE (-450 -2625);
FORCEPROP 2 LAST $SEC 1
J 0
(-450 -2625);
DISPLAY 0.680851 (-450 -2625);
PAINT MONO (-450 -2625);
DISPLAY INVISIBLE (-450 -2625);
FORCEPROP 2 LAST CDS_SEC 1
J 0
(-450 -2625);
DISPLAY 1.021277 (-450 -2625);
DISPLAY INVISIBLE (-450 -2625);
FORCEADD UNIVERSAL_POWER..1
(-500 -2550);
FORCEPROP 3 LASTPIN (-500 -2600) SIG_NAME P3V3_AUX\g
J 0
(-490 -2590);
DISPLAY 0.659574 (-490 -2590);
PAINT MONO (-490 -2590);
DISPLAY INVISIBLE (-490 -2590);
FORCEPROP 1 LAST HDL_POWER P3V3_AUX
J 1
(-500 -2500);
DISPLAY 0.872340 (-500 -2500);
PAINT GREEN (-500 -2500);
FORCEPROP 2 LAST CDS_LIB logical_power
J 0
(-500 -2550);
PAINT MONO (-500 -2550);
DISPLAY INVISIBLE (-500 -2550);
FORCEPROP 1 LAST PATH I22
J 0
(-450 -2525);
DISPLAY 0.872340 (-450 -2525);
PAINT AQUA (-450 -2525);
DISPLAY INVISIBLE (-450 -2525);
FORCEADD UNIVERSAL_GND..1
(-500 -2125);
FORCEPROP 3 LASTPIN (-500 -2075) SIG_NAME GND\g
J 0
(-490 -2065);
DISPLAY 0.659574 (-490 -2065);
PAINT MONO (-490 -2065);
DISPLAY INVISIBLE (-490 -2065);
FORCEPROP 1 LAST HDL_POWER GND
J 1
(-475 -2200);
DISPLAY 0.872340 (-475 -2200);
PAINT GREEN (-475 -2200);
DISPLAY INVISIBLE (-475 -2200);
FORCEPROP 2 LAST CDS_LIB logical_power
J 0
(-500 -2125);
PAINT MONO (-500 -2125);
DISPLAY INVISIBLE (-500 -2125);
FORCEPROP 1 LAST PATH I23
J 0
(-425 -2125);
DISPLAY 0.872340 (-425 -2125);
PAINT AQUA (-425 -2125);
DISPLAY INVISIBLE (-425 -2125);
FORCEADD UNIVERSAL_GND..1
(-1575 -2025);
FORCEPROP 3 LASTPIN (-1575 -1975) SIG_NAME GND\g
J 0
(-1565 -1965);
DISPLAY 0.659574 (-1565 -1965);
PAINT MONO (-1565 -1965);
DISPLAY INVISIBLE (-1565 -1965);
FORCEPROP 1 LAST HDL_POWER GND
J 1
(-1550 -2100);
DISPLAY 0.872340 (-1550 -2100);
PAINT GREEN (-1550 -2100);
DISPLAY INVISIBLE (-1550 -2100);
FORCEPROP 2 LAST CDS_LIB logical_power
J 0
(-1575 -2025);
PAINT MONO (-1575 -2025);
DISPLAY INVISIBLE (-1575 -2025);
FORCEPROP 1 LAST PATH I24
J 0
(-1500 -2025);
DISPLAY 0.872340 (-1500 -2025);
PAINT AQUA (-1500 -2025);
DISPLAY INVISIBLE (-1500 -2025);
FORCEADD 74LVC2G07DW7..1
(-1175 -1750);
FORCEPROP 1 LAST PART_NUMBER AL002G07003
J 0
(-1344 -1516);
DISPLAY 0.723404 (-1344 -1516);
PAINT GREEN (-1344 -1516);
DISPLAY INVISIBLE (-1344 -1516);
FORCEPROP 2 LAST PART_TYPE SMLF
J 0
(-1325 -1275);
DISPLAY 1.021277 (-1325 -1275);
FORCEPROP 2 LAST VALUE 74LVC2G07DW-7
J 0
(-1325 -1325);
DISPLAY 1.021277 (-1325 -1325);
FORCEPROP 1 LAST MATERIAL IC
J 0
(-1344 -1643);
DISPLAY 0.723404 (-1344 -1643);
PAINT GREEN (-1344 -1643);
FORCEPROP 1 LAST LOCATION U58
J 0
(-1344 -1369);
DISPLAY 0.723404 (-1344 -1369);
PAINT GREEN (-1344 -1369);
FORCEPROP 0 LASTPIN (-1500 -1700) $PN 1
J 2
(-1510 -1690);
DISPLAY 0.680851 (-1510 -1690);
PAINT MONO (-1510 -1690);
FORCEPROP 0 LASTPIN (-850 -1700) $PN 6
J 0
(-840 -1690);
DISPLAY 0.680851 (-840 -1690);
PAINT MONO (-840 -1690);
FORCEPROP 0 LASTPIN (-1500 -1800) $PN 3
J 2
(-1510 -1790);
DISPLAY 0.680851 (-1510 -1790);
PAINT MONO (-1510 -1790);
FORCEPROP 0 LASTPIN (-850 -1800) $PN 4
J 0
(-840 -1790);
DISPLAY 0.680851 (-840 -1790);
PAINT MONO (-840 -1790);
FORCEPROP 0 LASTPIN (-1500 -1750) $PN 2
J 2
(-1510 -1740);
DISPLAY 0.680851 (-1510 -1740);
PAINT MONO (-1510 -1740);
FORCEPROP 0 LASTPIN (-850 -1750) $PN 5
J 0
(-840 -1740);
DISPLAY 0.680851 (-840 -1740);
PAINT MONO (-840 -1740);
FORCEPROP 1 LAST NEEDS_NO_SIZE TRUE
J 0
(-1175 -1750);
DISPLAY 0.723404 (-1175 -1750);
PAINT GREEN (-1175 -1750);
DISPLAY INVISIBLE (-1175 -1750);
FORCEPROP 1 LAST CDS_LMAN_SYM_OUTLINE -175,100,175,-100
J 0
(-1175 -1750);
DISPLAY 0.468085 (-1175 -1750);
PAINT GREEN (-1175 -1750);
DISPLAY INVISIBLE (-1175 -1750);
FORCEPROP 2 LAST CDS_LIB pure_quanta
J 0
(-1175 -1750);
DISPLAY INVISIBLE (-1175 -1750);
FORCEPROP 1 LAST PATH I25
J 0
(-1175 -1750);
DISPLAY 0.723404 (-1175 -1750);
PAINT GREEN (-1175 -1750);
DISPLAY INVISIBLE (-1175 -1750);
FORCEPROP 0 LAST $SEC 1
J 0
(-1325 -1225);
DISPLAY 0.680851 (-1325 -1225);
PAINT MONO (-1325 -1225);
DISPLAY INVISIBLE (-1325 -1225);
FORCEPROP 0 LAST CDS_SEC 1
J 0
(-1325 -1225);
DISPLAY 1.021277 (-1325 -1225);
DISPLAY INVISIBLE (-1325 -1225);
FORCEADD Q_CAP..1
(-500 -1925);
FORCEPROP 1 LAST PART_NUMBER CH4104K1B00
J 0
(-450 -2075);
DISPLAY 0.510638 (-450 -2075);
DISPLAY INVISIBLE (-450 -2075);
FORCEPROP 1 LAST TOLERANCE 10%
J 0
(-450 -1975);
DISPLAY 0.510638 (-450 -1975);
FORCEPROP 1 LAST VOLTAGE 25V
J 0
(-450 -1925);
DISPLAY 0.510638 (-450 -1925);
FORCEPROP 1 LAST VALUE 0.1UF
J 0
(-450 -1875);
DISPLAY 0.510638 (-450 -1875);
FORCEPROP 1 LAST PACK_TYPE 0402
J 0
(-450 -2125);
DISPLAY 0.510638 (-450 -2125);
FORCEPROP 1 LAST MATERIAL X7R
J 0
(-450 -2025);
DISPLAY 0.510638 (-450 -2025);
FORCEPROP 1 LAST $LOCATION C1809
J 0
(-450 -1825);
DISPLAY 0.978723 (-450 -1825);
FORCEPROP 1 LASTPIN (-500 -1825) $PN 1
J 0
(-490 -1845);
DISPLAY 0.787234 (-490 -1845);
FORCEPROP 1 LASTPIN (-500 -2025) $PN 2
J 0
(-490 -2045);
DISPLAY 0.787234 (-490 -2045);
FORCEPROP 2 LAST CDS_LIB pure_quanta
J 0
(-500 -1925);
PAINT MONO (-500 -1925);
DISPLAY INVISIBLE (-500 -1925);
FORCEPROP 1 LAST PATH I26
J 0
(-450 -1775);
DISPLAY 0.978723 (-450 -1775);
PAINT WHITE (-450 -1775);
DISPLAY INVISIBLE (-450 -1775);
FORCEPROP 2 LAST CDS_LOCATION C1809
J 0
(-450 -1725);
DISPLAY 1.021277 (-450 -1725);
DISPLAY INVISIBLE (-450 -1725);
FORCEPROP 2 LAST $SEC 1
J 0
(-450 -1725);
DISPLAY 0.680851 (-450 -1725);
PAINT MONO (-450 -1725);
DISPLAY INVISIBLE (-450 -1725);
FORCEPROP 2 LAST CDS_SEC 1
J 0
(-450 -1725);
DISPLAY 1.021277 (-450 -1725);
DISPLAY INVISIBLE (-450 -1725);
FORCEADD UNIVERSAL_POWER..1
(-500 -1650);
FORCEPROP 3 LASTPIN (-500 -1700) SIG_NAME P3V3_AUX\g
J 0
(-490 -1690);
DISPLAY 0.659574 (-490 -1690);
PAINT MONO (-490 -1690);
DISPLAY INVISIBLE (-490 -1690);
FORCEPROP 1 LAST HDL_POWER P3V3_AUX
J 1
(-500 -1600);
DISPLAY 0.872340 (-500 -1600);
PAINT GREEN (-500 -1600);
FORCEPROP 2 LAST CDS_LIB logical_power
J 0
(-500 -1650);
PAINT MONO (-500 -1650);
DISPLAY INVISIBLE (-500 -1650);
FORCEPROP 1 LAST PATH I27
J 0
(-450 -1625);
DISPLAY 0.872340 (-450 -1625);
PAINT AQUA (-450 -1625);
DISPLAY INVISIBLE (-450 -1625);
FORCEADD GND..1
(-175 -1300);
FORCEPROP 3 LASTPIN (-175 -1250) SIG_NAME GND\g
J 0
(-165 -1240);
DISPLAY 0.659574 (-165 -1240);
PAINT MONO (-165 -1240);
DISPLAY INVISIBLE (-165 -1240);
FORCEPROP 1 LAST HDL_POWER GND
J 0
(-175 -1150);
DISPLAY 0.872340 (-175 -1150);
PAINT GREEN (-175 -1150);
DISPLAY INVISIBLE (-175 -1150);
FORCEPROP 1 LAST SIZE 1B
J 0
(-100 -1350);
DISPLAY 0.872340 (-100 -1350);
PAINT GREEN (-100 -1350);
DISPLAY INVISIBLE (-100 -1350);
FORCEPROP 2 LAST CDS_LIB logical_power
J 0
(-175 -1300);
DISPLAY INVISIBLE (-175 -1300);
FORCEPROP 1 LAST PATH I28
J 0
(-100 -1300);
DISPLAY 0.872340 (-100 -1300);
PAINT AQUA (-100 -1300);
DISPLAY INVISIBLE (-100 -1300);
FORCEADD Q_RES..2
(-175 -1050);
FORCEPROP 1 LAST PART_NUMBER CS31502FB05
J 0
(-125 -1100);
DISPLAY 0.404255 (-125 -1100);
DISPLAY INVISIBLE (-125 -1100);
FORCEPROP 1 LAST MATERIAL EMPTY
J 0
(-125 -1075);
DISPLAY 0.404255 (-125 -1075);
PAINT RED (-125 -1075);
FORCEPROP 1 LAST PACK_TYPE 0402LF
J 0
(-125 -1125);
DISPLAY 0.404255 (-125 -1125);
FORCEPROP 1 LAST VALUE 15K
J 0
(-125 -1000);
DISPLAY 0.404255 (-125 -1000);
FORCEPROP 1 LAST WATTAGE 1/16W
J 0
(-125 -1050);
DISPLAY 0.404255 (-125 -1050);
FORCEPROP 1 LAST TOLERANCE 1%
J 0
(-125 -1025);
DISPLAY 0.404255 (-125 -1025);
FORCEPROP 2 LAST ROOM NIC1_P12V_MAM_MAM_BOM1
J 0
(-125 -925);
DISPLAY 1.021277 (-125 -925);
FORCEPROP 1 LAST LOCATION PR3828
J 0
(-125 -975);
DISPLAY 0.638298 (-125 -975);
FORCEPROP 1 LASTPIN (-175 -950) $PN 1
J 0
(-170 -988);
DISPLAY 0.787234 (-170 -988);
PAINT MONO (-170 -988);
FORCEPROP 1 LASTPIN (-175 -1150) $PN 2
J 0
(-170 -1140);
DISPLAY 0.787234 (-170 -1140);
PAINT MONO (-170 -1140);
FORCEPROP 1 LAST PATH I29
J 0
(-125 -875);
DISPLAY 0.978723 (-125 -875);
PAINT WHITE (-125 -875);
DISPLAY INVISIBLE (-125 -875);
FORCEPROP 2 LAST CDS_LIB pure_quanta
J 0
(-175 -1050);
DISPLAY INVISIBLE (-175 -1050);
FORCEPROP 2 LAST ROOM1 NIC1_P12V_MAM_TIC_BOM2
J 0
(-125 -875);
DISPLAY 1.021277 (-125 -875);
DISPLAY INVISIBLE (-125 -875);
FORCEPROP 0 LAST $SEC 1
J 0
(-125 -925);
DISPLAY 0.680851 (-125 -925);
PAINT MONO (-125 -925);
DISPLAY INVISIBLE (-125 -925);
FORCEPROP 0 LAST CDS_SEC 1
J 0
(-125 -925);
DISPLAY 1.021277 (-125 -925);
DISPLAY INVISIBLE (-125 -925);
FORCEADD Q_RES..2
(-2550 -2350);
FORCEPROP 1 LAST PART_NUMBER CS21002FB06
J 0
(-2510 -2475);
DISPLAY 0.638298 (-2510 -2475);
DISPLAY INVISIBLE (-2510 -2475);
FORCEPROP 1 LAST WATTAGE 1/16W
J 0
(-2510 -2375);
DISPLAY 0.638298 (-2510 -2375);
FORCEPROP 1 LAST TOLERANCE 1%
J 0
(-2505 -2325);
DISPLAY 0.638298 (-2505 -2325);
FORCEPROP 1 LAST VALUE 1K
J 0
(-2505 -2275);
DISPLAY 0.638298 (-2505 -2275);
FORCEPROP 1 LAST MATERIAL CHIP
J 0
(-2510 -2425);
DISPLAY 0.638298 (-2510 -2425);
FORCEPROP 1 LAST PACK_TYPE 0402LF
J 0
(-2510 -2475);
DISPLAY 0.638298 (-2510 -2475);
FORCEPROP 1 LAST LOCATION R3134
J 0
(-2505 -2225);
DISPLAY 0.978723 (-2505 -2225);
FORCEPROP 1 LASTPIN (-2550 -2250) $PN 1
J 0
(-2545 -2288);
DISPLAY 0.787234 (-2545 -2288);
PAINT MONO (-2545 -2288);
FORCEPROP 1 LASTPIN (-2550 -2450) $PN 2
J 0
(-2545 -2440);
DISPLAY 0.787234 (-2545 -2440);
PAINT MONO (-2545 -2440);
FORCEPROP 2 LAST CDS_LIB pure_quanta
J 0
(-2550 -2350);
DISPLAY INVISIBLE (-2550 -2350);
FORCEPROP 1 LAST PATH I3
J 0
(-2500 -2175);
DISPLAY 0.978723 (-2500 -2175);
PAINT WHITE (-2500 -2175);
DISPLAY INVISIBLE (-2500 -2175);
FORCEPROP 0 LAST $SEC 1
J 0
(-2500 -2175);
DISPLAY 0.680851 (-2500 -2175);
PAINT MONO (-2500 -2175);
DISPLAY INVISIBLE (-2500 -2175);
FORCEPROP 0 LAST CDS_SEC 1
J 0
(-2500 -2175);
DISPLAY 1.021277 (-2500 -2175);
DISPLAY INVISIBLE (-2500 -2175);
FORCEADD Q_RES..1
(-775 -425);
FORCEPROP 1 LAST PART_NUMBER CS00002JB13
J 0
(-850 -475);
DISPLAY 0.510638 (-850 -475);
DISPLAY INVISIBLE (-850 -475);
FORCEPROP 1 LAST WATTAGE 1/16W
J 2
(-575 -500);
DISPLAY 0.510638 (-575 -500);
FORCEPROP 1 LAST VALUE 0
J 2
(-625 -425);
DISPLAY 0.510638 (-625 -425);
FORCEPROP 1 LAST TOLERANCE 5%
J 0
(-600 -425);
DISPLAY 0.510638 (-600 -425);
FORCEPROP 1 LAST MATERIAL EMPTY
J 0
(-850 -500);
DISPLAY 0.510638 (-850 -500);
PAINT RED (-850 -500);
FORCEPROP 1 LAST PACK_TYPE 0402LF
J 0
(-500 -425);
DISPLAY 0.510638 (-500 -425);
FORCEPROP 2 LAST ROOM NIC1_P12V_MAM_MAM_BOM1
J 0
(-825 -325);
DISPLAY 1.021277 (-825 -325);
FORCEPROP 1 LAST $LOCATION R3827
J 0
(-825 -375);
DISPLAY 0.978723 (-825 -375);
FORCEPROP 1 LASTPIN (-875 -425) $PN 1
J 0
(-863 -413);
DISPLAY 0.787234 (-863 -413);
PAINT MONO (-863 -413);
FORCEPROP 1 LASTPIN (-675 -425) $PN 2
J 0
(-713 -413);
DISPLAY 0.787234 (-713 -413);
PAINT MONO (-713 -413);
FORCEPROP 1 LAST PATH I30
J 0
(-825 -275);
DISPLAY 0.978723 (-825 -275);
PAINT WHITE (-825 -275);
DISPLAY INVISIBLE (-825 -275);
FORCEPROP 2 LAST CDS_LIB pure_quanta
J 0
(-775 -425);
DISPLAY INVISIBLE (-775 -425);
FORCEPROP 2 LAST ROOM1 NIC1_P12V_MAM_TIC_BOM2
J 0
(-825 -275);
DISPLAY 1.021277 (-825 -275);
DISPLAY INVISIBLE (-825 -275);
FORCEPROP 0 LAST CDS_LOCATION R3827
J 0
(-825 -325);
DISPLAY 1.021277 (-825 -325);
DISPLAY INVISIBLE (-825 -325);
FORCEPROP 0 LAST $SEC 1
J 0
(-825 -325);
DISPLAY 0.680851 (-825 -325);
PAINT MONO (-825 -325);
DISPLAY INVISIBLE (-825 -325);
FORCEPROP 0 LAST CDS_SEC 1
J 0
(-825 -325);
DISPLAY 1.021277 (-825 -325);
DISPLAY INVISIBLE (-825 -325);
FORCEADD GND..1
(-750 -175);
FORCEPROP 3 LASTPIN (-750 -125) SIG_NAME GND\g
J 0
(-740 -115);
DISPLAY 0.659574 (-740 -115);
PAINT MONO (-740 -115);
DISPLAY INVISIBLE (-740 -115);
FORCEPROP 1 LAST HDL_POWER GND
J 0
(-750 -25);
DISPLAY 0.872340 (-750 -25);
PAINT GREEN (-750 -25);
DISPLAY INVISIBLE (-750 -25);
FORCEPROP 2 LAST CDS_LIB logical_power
J 0
(-750 -175);
DISPLAY INVISIBLE (-750 -175);
FORCEPROP 1 LAST SIZE 1B
J 0
(-675 -225);
DISPLAY 0.872340 (-675 -225);
PAINT GREEN (-675 -225);
DISPLAY INVISIBLE (-675 -225);
FORCEPROP 1 LAST PATH I31
J 0
(-675 -175);
DISPLAY 0.872340 (-675 -175);
PAINT AQUA (-675 -175);
DISPLAY INVISIBLE (-675 -175);
FORCEADD Q_RES..2
(-175 -775);
FORCEPROP 1 LAST PART_NUMBER CS26802FB02
J 0
(-125 -825);
DISPLAY 0.404255 (-125 -825);
DISPLAY INVISIBLE (-125 -825);
FORCEPROP 1 LAST VALUE 6.8K
J 0
(-125 -725);
DISPLAY 0.404255 (-125 -725);
FORCEPROP 1 LAST TOLERANCE 1%
J 0
(-125 -750);
DISPLAY 0.404255 (-125 -750);
FORCEPROP 1 LAST WATTAGE 1/16W
J 0
(-125 -775);
DISPLAY 0.404255 (-125 -775);
FORCEPROP 2 LAST ROOM NIC1_P12V_MAM_MAM_BOM1
J 0
(-125 -650);
DISPLAY 1.021277 (-125 -650);
FORCEPROP 1 LAST MATERIAL EMPTY
J 0
(-125 -800);
DISPLAY 0.404255 (-125 -800);
PAINT RED (-125 -800);
FORCEPROP 1 LAST PACK_TYPE 0402LF
J 0
(-125 -850);
DISPLAY 0.404255 (-125 -850);
FORCEPROP 1 LAST LOCATION PR3806
J 0
(-125 -700);
DISPLAY 0.638298 (-125 -700);
FORCEPROP 1 LASTPIN (-175 -675) $PN 1
J 0
(-170 -713);
DISPLAY 0.787234 (-170 -713);
PAINT MONO (-170 -713);
FORCEPROP 1 LASTPIN (-175 -875) $PN 2
J 0
(-170 -865);
DISPLAY 0.787234 (-170 -865);
PAINT MONO (-170 -865);
FORCEPROP 1 LAST PATH I32
J 0
(-125 -600);
DISPLAY 0.978723 (-125 -600);
PAINT WHITE (-125 -600);
DISPLAY INVISIBLE (-125 -600);
FORCEPROP 2 LAST CDS_LIB pure_quanta
J 0
(-175 -775);
DISPLAY INVISIBLE (-175 -775);
FORCEPROP 2 LAST ROOM1 NIC1_P12V_MAM_TIC_BOM2
J 0
(-125 -600);
DISPLAY 1.021277 (-125 -600);
DISPLAY INVISIBLE (-125 -600);
FORCEPROP 0 LAST $SEC 1
J 0
(-125 -650);
DISPLAY 0.680851 (-125 -650);
PAINT MONO (-125 -650);
DISPLAY INVISIBLE (-125 -650);
FORCEPROP 0 LAST CDS_SEC 1
J 0
(-125 -650);
DISPLAY 1.021277 (-125 -650);
DISPLAY INVISIBLE (-125 -650);
FORCEADD Q_RES..2
(-175 -100);
FORCEPROP 1 LAST PART_NUMBER CS41602FB05
J 0
(-125 -150);
DISPLAY 0.404255 (-125 -150);
DISPLAY INVISIBLE (-125 -150);
FORCEPROP 1 LAST VALUE 160K
J 0
(-125 -50);
DISPLAY 0.404255 (-125 -50);
FORCEPROP 1 LAST WATTAGE 1/16W
J 0
(-125 -100);
DISPLAY 0.404255 (-125 -100);
FORCEPROP 1 LAST MATERIAL EMPTY
J 0
(-125 -125);
DISPLAY 0.404255 (-125 -125);
PAINT RED (-125 -125);
FORCEPROP 1 LAST PACK_TYPE 0402LF
J 0
(-125 -175);
DISPLAY 0.404255 (-125 -175);
FORCEPROP 1 LAST TOLERANCE 1%
J 0
(-125 -75);
DISPLAY 0.404255 (-125 -75);
FORCEPROP 2 LAST ROOM NIC1_P12V_MAM_MAM_BOM1
J 0
(-125 25);
DISPLAY 1.021277 (-125 25);
FORCEPROP 1 LAST LOCATION PR3805
J 0
(-125 -25);
DISPLAY 0.638298 (-125 -25);
FORCEPROP 1 LASTPIN (-175 0) $PN 1
J 0
(-170 -38);
DISPLAY 0.787234 (-170 -38);
PAINT MONO (-170 -38);
FORCEPROP 1 LASTPIN (-175 -200) $PN 2
J 0
(-170 -190);
DISPLAY 0.787234 (-170 -190);
PAINT MONO (-170 -190);
FORCEPROP 1 LAST PATH I33
J 0
(-125 75);
DISPLAY 0.978723 (-125 75);
PAINT WHITE (-125 75);
DISPLAY INVISIBLE (-125 75);
FORCEPROP 2 LAST CDS_LIB pure_quanta
J 0
(-175 -100);
DISPLAY INVISIBLE (-175 -100);
FORCEPROP 2 LAST ROOM1 NIC1_P12V_MAM_TIC_BOM2
J 0
(-125 75);
DISPLAY 1.021277 (-125 75);
DISPLAY INVISIBLE (-125 75);
FORCEPROP 0 LAST $SEC 1
J 0
(-125 25);
DISPLAY 0.680851 (-125 25);
PAINT MONO (-125 25);
DISPLAY INVISIBLE (-125 25);
FORCEPROP 0 LAST CDS_SEC 1
J 0
(-125 25);
DISPLAY 1.021277 (-125 25);
DISPLAY INVISIBLE (-125 25);
FORCEADD OFFPAGE..1
(-4150 1000);
PAINT AQUA (-4150 1000);
FORCEPROP 2 LAST $XR2 238 
J 0
(-4642 1000);
DISPLAY 0.638298 (-4642 1000);
PAINT MONO (-4642 1000);
FORCEPROP 2 LAST $XR1 163 
J 0
(-4522 1000);
DISPLAY 0.638298 (-4522 1000);
PAINT MONO (-4522 1000);
FORCEPROP 2 LAST $XR0 164 
J 0
(-4402 1000);
DISPLAY 0.638298 (-4402 1000);
PAINT MONO (-4402 1000);
FORCEPROP 1 LAST COMMENT_BODY TRUE
J 0
(-4025 900);
DISPLAY 0.872340 (-4025 900);
PAINT GREEN (-4025 900);
DISPLAY INVISIBLE (-4025 900);
FORCEPROP 1 LAST OFFPAGE TRUE
J 0
(-3825 875);
DISPLAY 0.872340 (-3825 875);
PAINT AQUA (-3825 875);
DISPLAY INVISIBLE (-3825 875);
FORCEPROP 2 LAST CDS_LIB standard
J 0
(-4150 1000);
DISPLAY INVISIBLE (-4150 1000);
FORCEPROP 2 LAST PATH I34
J 0
(-4400 1050);
DISPLAY 1.021277 (-4400 1050);
DISPLAY INVISIBLE (-4400 1050);
FORCEADD Q_RES..1
(-3275 1300);
FORCEPROP 1 LAST PART_NUMBER CS00002JB13
J 0
(-3575 1225);
DISPLAY 0.595745 (-3575 1225);
DISPLAY INVISIBLE (-3575 1225);
FORCEPROP 1 LAST VALUE 0
J 2
(-3125 1300);
DISPLAY 0.595745 (-3125 1300);
FORCEPROP 1 LAST TOLERANCE 5%
J 0
(-3100 1300);
DISPLAY 0.595745 (-3100 1300);
FORCEPROP 1 LAST PACK_TYPE 0402LF
J 0
(-3200 1225);
DISPLAY 0.595745 (-3200 1225);
FORCEPROP 1 LAST WATTAGE 1/16W
J 2
(-3075 1175);
DISPLAY 0.595745 (-3075 1175);
FORCEPROP 1 LAST MATERIAL CHIP
J 0
(-3400 1175);
DISPLAY 0.595745 (-3400 1175);
FORCEPROP 1 LAST $LOCATION R4060
J 0
(-3500 1300);
DISPLAY 0.638298 (-3500 1300);
FORCEPROP 2 LAST CDS_LIB pure_quanta
J 0
(-3275 1300);
DISPLAY INVISIBLE (-3275 1300);
FORCEPROP 1 LAST PATH I35
J 0
(-3325 1450);
DISPLAY 0.978723 (-3325 1450);
PAINT WHITE (-3325 1450);
DISPLAY INVISIBLE (-3325 1450);
FORCEPROP 0 LAST CDS_LOCATION R4060
J 0
(-3200 1375);
DISPLAY INVISIBLE (-3200 1375);
FORCEPROP 0 LAST $SEC 1
J 0
(-3200 1375);
DISPLAY INVISIBLE (-3200 1375);
FORCEPROP 0 LAST CDS_SEC 1
J 0
(-3200 1375);
DISPLAY INVISIBLE (-3200 1375);
FORCEPROP 1 LASTPIN (-3375 1300) $PN 1
J 0
(-3363 1312);
DISPLAY 0.787234 (-3363 1312);
PAINT MONO (-3363 1312);
DISPLAY INVISIBLE (-3363 1312);
FORCEPROP 1 LASTPIN (-3175 1300) $PN 2
J 0
(-3213 1312);
DISPLAY 0.787234 (-3213 1312);
PAINT MONO (-3213 1312);
DISPLAY INVISIBLE (-3213 1312);
FORCEADD GND..1
(-2825 750);
FORCEPROP 3 LASTPIN (-2825 800) SIG_NAME GND\g
J 0
(-2815 810);
DISPLAY 0.659574 (-2815 810);
PAINT MONO (-2815 810);
DISPLAY INVISIBLE (-2815 810);
FORCEPROP 1 LAST SIZE 1B
J 0
(-2750 700);
DISPLAY 0.872340 (-2750 700);
PAINT GREEN (-2750 700);
DISPLAY INVISIBLE (-2750 700);
FORCEPROP 2 LAST CDS_LIB logical_power
J 0
(-2825 750);
DISPLAY INVISIBLE (-2825 750);
FORCEPROP 1 LAST HDL_POWER GND
J 0
(-2825 900);
DISPLAY 0.872340 (-2825 900);
PAINT GREEN (-2825 900);
DISPLAY INVISIBLE (-2825 900);
FORCEPROP 1 LAST PATH I36
J 0
(-2750 750);
DISPLAY 0.872340 (-2750 750);
PAINT AQUA (-2750 750);
DISPLAY INVISIBLE (-2750 750);
FORCEADD Q_RES..2
(-2825 975);
FORCEPROP 1 LAST PART_NUMBER CS24702JB10
J 0
(-2785 800);
DISPLAY 0.638298 (-2785 800);
DISPLAY INVISIBLE (-2785 800);
FORCEPROP 1 LAST WATTAGE 1/16W
J 0
(-2785 950);
DISPLAY 0.638298 (-2785 950);
FORCEPROP 1 LAST MATERIAL CHIP
J 0
(-2785 900);
DISPLAY 0.638298 (-2785 900);
FORCEPROP 1 LAST PACK_TYPE 0402LF
J 0
(-2785 850);
DISPLAY 0.638298 (-2785 850);
FORCEPROP 1 LAST TOLERANCE 5%
J 0
(-2780 1000);
DISPLAY 0.638298 (-2780 1000);
FORCEPROP 1 LAST VALUE 4.7K
J 0
(-2780 1050);
DISPLAY 0.638298 (-2780 1050);
FORCEPROP 1 LAST $LOCATION R4066
J 0
(-2780 1100);
DISPLAY 0.978723 (-2780 1100);
FORCEPROP 1 LASTPIN (-2825 1075) $PN 1
J 0
(-2820 1037);
DISPLAY 0.787234 (-2820 1037);
PAINT MONO (-2820 1037);
FORCEPROP 1 LASTPIN (-2825 875) $PN 2
J 0
(-2820 885);
DISPLAY 0.787234 (-2820 885);
PAINT MONO (-2820 885);
FORCEPROP 2 LAST CDS_LIB pure_quanta
J 0
(-2825 975);
DISPLAY INVISIBLE (-2825 975);
FORCEPROP 1 LAST PATH I37
J 0
(-2775 1150);
DISPLAY 0.978723 (-2775 1150);
PAINT WHITE (-2775 1150);
DISPLAY INVISIBLE (-2775 1150);
FORCEPROP 0 LAST CDS_LOCATION R4066
J 0
(-2775 1150);
DISPLAY 1.021277 (-2775 1150);
DISPLAY INVISIBLE (-2775 1150);
FORCEPROP 0 LAST $SEC 1
J 0
(-2775 1150);
DISPLAY 0.680851 (-2775 1150);
PAINT MONO (-2775 1150);
DISPLAY INVISIBLE (-2775 1150);
FORCEPROP 0 LAST CDS_SEC 1
J 0
(-2775 1150);
DISPLAY 1.021277 (-2775 1150);
DISPLAY INVISIBLE (-2775 1150);
FORCEADD MOSFET_NCH_DUAL..1
(-2375 1350);
FORCEPROP 1 LAST PART_NUMBER BAM138K0003
J 0
(-2224 1264);
DISPLAY 0.723404 (-2224 1264);
PAINT GREEN (-2224 1264);
DISPLAY INVISIBLE (-2224 1264);
FORCEPROP 2 LAST PART_TYPE SMLF
J 0
(-2200 1425);
DISPLAY 1.021277 (-2200 1425);
FORCEPROP 2 LAST VALUE PJT138K
J 0
(-2200 1375);
DISPLAY 1.021277 (-2200 1375);
FORCEPROP 1 LAST MATERIAL IC
J 0
(-2224 1199);
DISPLAY 0.723404 (-2224 1199);
PAINT GREEN (-2224 1199);
FORCEPROP 2 LAST ROOM NIC1_P3V3_BOM1
J 0
(-2200 1475);
DISPLAY 0.510638 (-2200 1475);
FORCEPROP 1 LAST $LOCATION Q119
J 0
(-2224 1324);
DISPLAY 0.723404 (-2224 1324);
PAINT GREEN (-2224 1324);
FORCEPROP 0 LASTPIN (-2325 1550) $PN 6
R 1
J 0
(-2335 1560);
DISPLAY 0.680851 (-2335 1560);
PAINT MONO (-2335 1560);
FORCEPROP 0 LASTPIN (-2575 1300) $PN 2
J 2
(-2585 1310);
DISPLAY 0.680851 (-2585 1310);
PAINT MONO (-2585 1310);
FORCEPROP 0 LASTPIN (-2325 1150) $PN 1
R 1
J 2
(-2335 1140);
DISPLAY 0.680851 (-2335 1140);
PAINT MONO (-2335 1140);
FORCEPROP 1 LAST PATH I38
J 0
(-2375 1350);
DISPLAY 0.723404 (-2375 1350);
PAINT GREEN (-2375 1350);
DISPLAY INVISIBLE (-2375 1350);
FORCEPROP 1 LAST NEEDS_NO_SIZE TRUE
J 0
(-2375 1349);
DISPLAY 0.468085 (-2375 1349);
PAINT GREEN (-2375 1349);
DISPLAY INVISIBLE (-2375 1349);
FORCEPROP 1 LAST CDS_LMAN_SYM_OUTLINE -150,150,150,-150
J 0
(-2375 1350);
DISPLAY 0.468085 (-2375 1350);
PAINT GREEN (-2375 1350);
DISPLAY INVISIBLE (-2375 1350);
FORCEPROP 2 LAST CDS_LIB pure_quanta
J 0
(-2375 1350);
DISPLAY INVISIBLE (-2375 1350);
FORCEPROP 0 LAST CDS_LOCATION Q119
J 0
(-2200 1475);
DISPLAY 1.021277 (-2200 1475);
DISPLAY INVISIBLE (-2200 1475);
FORCEPROP 0 LAST $SEC 1
J 0
(-2200 1475);
DISPLAY 0.680851 (-2200 1475);
PAINT MONO (-2200 1475);
DISPLAY INVISIBLE (-2200 1475);
FORCEPROP 0 LAST CDS_SEC 1
J 0
(-2200 1475);
DISPLAY 1.021277 (-2200 1475);
DISPLAY INVISIBLE (-2200 1475);
FORCEADD GND..1
(-2325 1000);
FORCEPROP 3 LASTPIN (-2325 1050) SIG_NAME GND\g
J 0
(-2315 1060);
DISPLAY 0.659574 (-2315 1060);
PAINT MONO (-2315 1060);
DISPLAY INVISIBLE (-2315 1060);
FORCEPROP 2 LAST CDS_LIB logical_power
J 0
(-2325 1000);
DISPLAY INVISIBLE (-2325 1000);
FORCEPROP 1 LAST SIZE 1B
J 0
(-2250 950);
DISPLAY 0.872340 (-2250 950);
PAINT GREEN (-2250 950);
DISPLAY INVISIBLE (-2250 950);
FORCEPROP 1 LAST HDL_POWER GND
J 0
(-2325 1150);
DISPLAY 0.872340 (-2325 1150);
PAINT GREEN (-2325 1150);
DISPLAY INVISIBLE (-2325 1150);
FORCEPROP 1 LAST PATH I39
J 0
(-2250 1000);
DISPLAY 0.872340 (-2250 1000);
PAINT AQUA (-2250 1000);
DISPLAY INVISIBLE (-2250 1000);
FORCEADD UNIVERSAL_POWER..1
(-2550 -2050);
FORCEPROP 3 LASTPIN (-2550 -2100) SIG_NAME P3V3_AUX\g
J 0
(-2540 -2090);
DISPLAY 0.659574 (-2540 -2090);
PAINT MONO (-2540 -2090);
DISPLAY INVISIBLE (-2540 -2090);
FORCEPROP 1 LAST HDL_POWER P3V3_AUX
J 1
(-2550 -2000);
DISPLAY 0.872340 (-2550 -2000);
PAINT GREEN (-2550 -2000);
FORCEPROP 2 LAST CDS_LIB logical_power
J 0
(-2550 -2050);
DISPLAY INVISIBLE (-2550 -2050);
FORCEPROP 1 LAST PATH I4
J 0
(-2500 -2025);
DISPLAY 0.872340 (-2500 -2025);
PAINT AQUA (-2500 -2025);
DISPLAY INVISIBLE (-2500 -2025);
FORCEADD Q_RES..2
(-2325 1950);
FORCEPROP 1 LAST PART_NUMBER CS31002FB08
J 0
(-2295 1867);
DISPLAY 0.638298 (-2295 1867);
DISPLAY INVISIBLE (-2295 1867);
FORCEPROP 1 LAST TOLERANCE 1%
J 0
(-2290 2017);
DISPLAY 0.638298 (-2290 2017);
FORCEPROP 1 LAST MATERIAL CHIP
J 0
(-2295 1917);
DISPLAY 0.638298 (-2295 1917);
FORCEPROP 1 LAST PACK_TYPE 0402LF
J 0
(-2295 1817);
DISPLAY 0.638298 (-2295 1817);
FORCEPROP 1 LAST VALUE 10K
J 0
(-2290 2067);
DISPLAY 0.638298 (-2290 2067);
FORCEPROP 1 LAST WATTAGE 1/16W
J 0
(-2295 1967);
DISPLAY 0.638298 (-2295 1967);
FORCEPROP 2 LAST ROOM NIC1_P3V3_BOM1
J 0
(-2275 2150);
DISPLAY 0.510638 (-2275 2150);
FORCEPROP 1 LAST $LOCATION R4067
J 0
(-2290 2117);
DISPLAY 0.638298 (-2290 2117);
FORCEPROP 1 LASTPIN (-2325 2050) $PN 1
J 0
(-2320 2012);
DISPLAY 0.787234 (-2320 2012);
PAINT MONO (-2320 2012);
FORCEPROP 1 LASTPIN (-2325 1850) $PN 2
J 0
(-2320 1860);
DISPLAY 0.787234 (-2320 1860);
PAINT MONO (-2320 1860);
FORCEPROP 1 LAST PATH I40
J 0
(-2275 2125);
DISPLAY 0.978723 (-2275 2125);
PAINT WHITE (-2275 2125);
DISPLAY INVISIBLE (-2275 2125);
FORCEPROP 2 LAST CDS_LIB pure_quanta
J 0
(-2325 1950);
DISPLAY INVISIBLE (-2325 1950);
FORCEPROP 0 LAST CDS_LOCATION R4067
J 0
(-2275 2150);
DISPLAY 1.021277 (-2275 2150);
DISPLAY INVISIBLE (-2275 2150);
FORCEPROP 0 LAST $SEC 1
J 0
(-2275 2150);
DISPLAY 0.680851 (-2275 2150);
PAINT MONO (-2275 2150);
DISPLAY INVISIBLE (-2275 2150);
FORCEPROP 0 LAST CDS_SEC 1
J 0
(-2275 2150);
DISPLAY 1.021277 (-2275 2150);
DISPLAY INVISIBLE (-2275 2150);
FORCEADD UNIVERSAL_POWER..1
(-2325 2200);
FORCEPROP 3 LASTPIN (-2325 2150) SIG_NAME P12V_AUX\g
J 0
(-2315 2160);
DISPLAY 0.659574 (-2315 2160);
PAINT MONO (-2315 2160);
DISPLAY INVISIBLE (-2315 2160);
FORCEPROP 1 LAST HDL_POWER P12V_AUX
J 1
(-2325 2250);
DISPLAY 0.872340 (-2325 2250);
PAINT GREEN (-2325 2250);
FORCEPROP 2 LAST CDS_LIB logical_power
J 0
(-2325 2200);
DISPLAY INVISIBLE (-2325 2200);
FORCEPROP 1 LAST PATH I41
J 0
(-2275 2225);
DISPLAY 0.872340 (-2275 2225);
PAINT AQUA (-2275 2225);
DISPLAY INVISIBLE (-2275 2225);
FORCEADD MOSFET_NCH_DUAL..2
(-1600 1425);
FORCEPROP 1 LAST PART_NUMBER BAM138K0003
J 0
(-1449 1331);
DISPLAY 0.723404 (-1449 1331);
PAINT GREEN (-1449 1331);
DISPLAY INVISIBLE (-1449 1331);
FORCEPROP 2 LAST PART_TYPE SMLF
J 0
(-1425 1500);
DISPLAY 1.021277 (-1425 1500);
FORCEPROP 1 LAST MATERIAL IC
J 0
(-1449 1276);
DISPLAY 0.723404 (-1449 1276);
PAINT GREEN (-1449 1276);
FORCEPROP 2 LAST VALUE PJT138K
J 0
(-1425 1450);
DISPLAY 1.021277 (-1425 1450);
FORCEPROP 2 LAST ROOM NIC1_P3V3_BOM1
J 0
(-1425 1550);
DISPLAY 0.638298 (-1425 1550);
FORCEPROP 1 LAST $LOCATION Q119
J 0
(-1449 1401);
DISPLAY 0.723404 (-1449 1401);
PAINT GREEN (-1449 1401);
FORCEPROP 0 LASTPIN (-1550 1625) $PN 3
R 1
J 0
(-1560 1635);
DISPLAY 0.680851 (-1560 1635);
PAINT MONO (-1560 1635);
FORCEPROP 0 LASTPIN (-1800 1375) $PN 5
J 2
(-1810 1385);
DISPLAY 0.680851 (-1810 1385);
PAINT MONO (-1810 1385);
FORCEPROP 0 LASTPIN (-1550 1225) $PN 4
R 1
J 2
(-1560 1215);
DISPLAY 0.680851 (-1560 1215);
PAINT MONO (-1560 1215);
FORCEPROP 1 LAST PATH I42
J 0
(-1450 1275);
DISPLAY 0.723404 (-1450 1275);
PAINT GREEN (-1450 1275);
DISPLAY INVISIBLE (-1450 1275);
FORCEPROP 2 LAST CDS_LIB pure_quanta
J 0
(-1600 1425);
DISPLAY INVISIBLE (-1600 1425);
FORCEPROP 1 LAST CDS_LMAN_SYM_OUTLINE -150,150,150,-150
J 0
(-1600 1425);
DISPLAY 0.468085 (-1600 1425);
PAINT GREEN (-1600 1425);
DISPLAY INVISIBLE (-1600 1425);
FORCEPROP 1 LAST NEEDS_NO_SIZE TRUE
J 0
(-1450 1316);
DISPLAY 0.468085 (-1450 1316);
PAINT GREEN (-1450 1316);
DISPLAY INVISIBLE (-1450 1316);
FORCEPROP 0 LAST CDS_LOCATION Q119
J 0
(-1425 1550);
DISPLAY 1.021277 (-1425 1550);
DISPLAY INVISIBLE (-1425 1550);
FORCEPROP 0 LAST $SEC 2
J 0
(-1425 1550);
DISPLAY 0.680851 (-1425 1550);
PAINT MONO (-1425 1550);
DISPLAY INVISIBLE (-1425 1550);
FORCEPROP 0 LAST CDS_SEC 2
J 0
(-1425 1550);
DISPLAY 1.021277 (-1425 1550);
DISPLAY INVISIBLE (-1425 1550);
FORCEADD GND..1
(-1550 1075);
FORCEPROP 3 LASTPIN (-1550 1125) SIG_NAME GND\g
J 0
(-1540 1135);
DISPLAY 0.659574 (-1540 1135);
PAINT MONO (-1540 1135);
DISPLAY INVISIBLE (-1540 1135);
FORCEPROP 1 LAST HDL_POWER GND
J 0
(-1550 1225);
DISPLAY 0.872340 (-1550 1225);
PAINT GREEN (-1550 1225);
DISPLAY INVISIBLE (-1550 1225);
FORCEPROP 1 LAST SIZE 1B
J 0
(-1475 1025);
DISPLAY 0.872340 (-1475 1025);
PAINT GREEN (-1475 1025);
DISPLAY INVISIBLE (-1475 1025);
FORCEPROP 2 LAST CDS_LIB logical_power
J 0
(-1550 1075);
DISPLAY INVISIBLE (-1550 1075);
FORCEPROP 1 LAST PATH I43
J 0
(-1475 1075);
DISPLAY 0.872340 (-1475 1075);
PAINT AQUA (-1475 1075);
DISPLAY INVISIBLE (-1475 1075);
FORCEADD DIODE_TVS..1
R 1
(-900 200);
FORCEPROP 1 LAST PART_NUMBER BCSMF14AZ01
J 0
(-845 117);
DISPLAY 0.574468 (-845 117);
PAINT GREEN (-845 117);
DISPLAY INVISIBLE (-845 117);
FORCEPROP 1 LAST MATERIAL IC
J 0
(-825 75);
DISPLAY 0.723404 (-825 75);
PAINT GREEN (-825 75);
FORCEPROP 2 LAST VALUE SMF14A
J 0
(-850 175);
DISPLAY 0.574468 (-850 175);
PAINT SKYBLUE (-850 175);
FORCEPROP 1 LAST LOCATION PD107
J 0
(-845 242);
DISPLAY 0.574468 (-845 242);
PAINT GREEN (-845 242);
FORCEPROP 0 LASTPIN (-900 50) $PN A
R 1
J 2
(-910 40);
DISPLAY 0.808511 (-910 40);
FORCEPROP 0 LASTPIN (-900 350) $PN C
R 1
J 0
(-910 360);
DISPLAY 0.808511 (-910 360);
FORCEPROP 2 LAST CDS_LIB pure_quanta
J 0
(-900 200);
DISPLAY INVISIBLE (-900 200);
FORCEPROP 1 LAST CDS_LMAN_SYM_OUTLINE -100,50,100,-50
R 1
J 0
(-900 200);
DISPLAY 0.468085 (-900 200);
PAINT GREEN (-900 200);
DISPLAY INVISIBLE (-900 200);
FORCEPROP 1 LASTPIN (-900 350) Pin_Length Short
R 1
J 0
(-890 375);
DISPLAY 0.489362 (-890 375);
PAINT MONO (-890 375);
DISPLAY INVISIBLE (-890 375);
FORCEPROP 0 LAST PART_TYPE SMLF
J 0
(-800 325);
DISPLAY 1.021277 (-800 325);
DISPLAY INVISIBLE (-800 325);
FORCEPROP 1 LAST PIN_NAMES_ROTATE True
R 1
J 0
(-900 200);
DISPLAY 0.489362 (-900 200);
PAINT GREEN (-900 200);
DISPLAY INVISIBLE (-900 200);
FORCEPROP 1 LAST PATH I44
R 1
J 0
(-850 300);
DISPLAY 0.723404 (-850 300);
PAINT GREEN (-850 300);
DISPLAY INVISIBLE (-850 300);
FORCEPROP 0 LAST $SEC 1
R 1
J 0
(-845 292);
DISPLAY INVISIBLE (-845 292);
FORCEPROP 0 LAST CDS_SEC 1
R 1
J 0
(-845 292);
DISPLAY INVISIBLE (-845 292);
FORCEADD UNIVERSAL_POWER..1
(-750 550);
FORCEPROP 3 LASTPIN (-750 500) SIG_NAME P12V_AUX\g
J 0
(-740 510);
DISPLAY 0.659574 (-740 510);
PAINT MONO (-740 510);
DISPLAY INVISIBLE (-740 510);
FORCEPROP 1 LAST HDL_POWER P12V_AUX
J 1
(-750 600);
DISPLAY 0.872340 (-750 600);
PAINT GREEN (-750 600);
FORCEPROP 2 LAST CDS_LIB logical_power
J 0
(-750 550);
DISPLAY INVISIBLE (-750 550);
FORCEPROP 1 LAST PATH I45
J 0
(-700 575);
DISPLAY 0.872340 (-700 575);
PAINT AQUA (-700 575);
DISPLAY INVISIBLE (-700 575);
FORCEADD Q_CAP..1
(-525 200);
FORCEPROP 1 LAST PART_NUMBER CH5104KEB02
J 0
(-475 150);
DISPLAY 0.510638 (-475 150);
DISPLAY INVISIBLE (-475 150);
FORCEPROP 1 LAST PACK_TYPE C0402
J 0
(-475 175);
DISPLAY 0.510638 (-475 175);
FORCEPROP 1 LAST VALUE 1UF
J 0
(-475 250);
DISPLAY 0.510638 (-475 250);
FORCEPROP 1 LAST MATERIAL X6S
J 0
(-475 200);
DISPLAY 0.510638 (-475 200);
FORCEPROP 1 LAST VOLTAGE 25V
J 0
(-475 225);
DISPLAY 0.510638 (-475 225);
FORCEPROP 1 LAST LOCATION PC2139
J 0
(-475 275);
DISPLAY 0.638298 (-475 275);
FORCEPROP 1 LAST TOLERANCE 10%
J 0
(-475 150);
DISPLAY 0.638298 (-475 150);
DISPLAY INVISIBLE (-475 150);
FORCEPROP 2 LAST CDS_LIB pure_quanta
J 0
(-525 200);
DISPLAY INVISIBLE (-525 200);
FORCEPROP 1 LAST PATH I46
J 0
(-475 350);
DISPLAY 0.978723 (-475 350);
PAINT WHITE (-475 350);
DISPLAY INVISIBLE (-475 350);
FORCEPROP 0 LAST $SEC 1
J 0
(-470 342);
DISPLAY INVISIBLE (-470 342);
FORCEPROP 0 LAST CDS_SEC 1
J 0
(-470 342);
DISPLAY INVISIBLE (-470 342);
FORCEPROP 1 LASTPIN (-525 300) $PN 1
J 0
(-515 280);
DISPLAY 0.787234 (-515 280);
PAINT MONO (-515 280);
DISPLAY INVISIBLE (-515 280);
FORCEPROP 1 LASTPIN (-525 100) $PN 2
J 0
(-515 80);
DISPLAY 0.787234 (-515 80);
PAINT MONO (-515 80);
DISPLAY INVISIBLE (-515 80);
FORCEADD Q_RES..1
(-550 1900);
FORCEPROP 1 LAST PART_NUMBER CS00002JB13
J 0
(-625 1850);
DISPLAY 0.510638 (-625 1850);
DISPLAY INVISIBLE (-625 1850);
FORCEPROP 1 LAST MATERIAL CHIP
J 0
(-625 1825);
DISPLAY 0.510638 (-625 1825);
FORCEPROP 1 LAST WATTAGE 1/16W
J 2
(-375 1825);
DISPLAY 0.510638 (-375 1825);
FORCEPROP 1 LAST TOLERANCE 5%
J 0
(-400 1900);
DISPLAY 0.510638 (-400 1900);
FORCEPROP 1 LAST PACK_TYPE 0402LF
J 0
(-325 1900);
DISPLAY 0.510638 (-325 1900);
FORCEPROP 1 LAST VALUE 0
J 2
(-425 1900);
DISPLAY 0.510638 (-425 1900);
FORCEPROP 2 LAST ROOM NIC1_P3V3_BOM1
J 0
(-750 1950);
DISPLAY 0.510638 (-750 1950);
FORCEPROP 1 LAST $LOCATION R3807
J 0
(-750 1900);
DISPLAY 0.638298 (-750 1900);
FORCEPROP 1 LASTPIN (-650 1900) $PN 1
J 0
(-638 1912);
DISPLAY 0.787234 (-638 1912);
PAINT MONO (-638 1912);
FORCEPROP 1 LASTPIN (-450 1900) $PN 2
J 0
(-488 1912);
DISPLAY 0.787234 (-488 1912);
PAINT MONO (-488 1912);
FORCEPROP 1 LAST PATH I47
J 0
(-600 2050);
DISPLAY 0.978723 (-600 2050);
PAINT WHITE (-600 2050);
DISPLAY INVISIBLE (-600 2050);
FORCEPROP 2 LAST CDS_LIB pure_quanta
J 0
(-550 1900);
DISPLAY INVISIBLE (-550 1900);
FORCEPROP 0 LAST CDS_LOCATION R3807
J 0
(-600 2000);
DISPLAY 1.021277 (-600 2000);
DISPLAY INVISIBLE (-600 2000);
FORCEPROP 0 LAST $SEC 1
J 0
(-600 2000);
DISPLAY 0.680851 (-600 2000);
PAINT MONO (-600 2000);
DISPLAY INVISIBLE (-600 2000);
FORCEPROP 0 LAST CDS_SEC 1
J 0
(-600 2000);
DISPLAY 1.021277 (-600 2000);
DISPLAY INVISIBLE (-600 2000);
FORCEADD Q_RES..2
(-50 1275);
FORCEPROP 1 LAST PART_NUMBER CS31502FB05
J 0
(0 1225);
DISPLAY 0.404255 (0 1225);
DISPLAY INVISIBLE (0 1225);
FORCEPROP 1 LAST WATTAGE 1/16W
J 0
(0 1275);
DISPLAY 0.404255 (0 1275);
FORCEPROP 1 LAST TOLERANCE 1%
J 0
(0 1300);
DISPLAY 0.404255 (0 1300);
FORCEPROP 1 LAST VALUE 15K
J 0
(0 1325);
DISPLAY 0.404255 (0 1325);
FORCEPROP 1 LAST PACK_TYPE 0402LF
J 0
(0 1200);
DISPLAY 0.404255 (0 1200);
FORCEPROP 1 LAST MATERIAL CHIP
J 0
(0 1250);
DISPLAY 0.404255 (0 1250);
FORCEPROP 2 LAST ROOM NIC1_P3V3_BOM1
J 0
(0 1150);
DISPLAY 0.510638 (0 1150);
FORCEPROP 1 LAST LOCATION PR3812
J 0
(0 1350);
DISPLAY 0.638298 (0 1350);
FORCEPROP 1 LASTPIN (-50 1375) $PN 1
J 0
(-45 1337);
DISPLAY 0.787234 (-45 1337);
PAINT MONO (-45 1337);
FORCEPROP 1 LASTPIN (-50 1175) $PN 2
J 0
(-45 1185);
DISPLAY 0.787234 (-45 1185);
PAINT MONO (-45 1185);
FORCEPROP 1 LAST PATH I48
J 0
(0 1450);
DISPLAY 0.978723 (0 1450);
PAINT WHITE (0 1450);
DISPLAY INVISIBLE (0 1450);
FORCEPROP 2 LAST CDS_LIB pure_quanta
J 0
(-50 1275);
DISPLAY INVISIBLE (-50 1275);
FORCEPROP 0 LAST $SEC 1
J 0
(0 1400);
DISPLAY 0.680851 (0 1400);
PAINT MONO (0 1400);
DISPLAY INVISIBLE (0 1400);
FORCEPROP 0 LAST CDS_SEC 1
J 0
(0 1400);
DISPLAY 1.021277 (0 1400);
DISPLAY INVISIBLE (0 1400);
FORCEADD GND..1
(-50 1025);
FORCEPROP 3 LASTPIN (-50 1075) SIG_NAME GND\g
J 0
(-40 1085);
DISPLAY 0.659574 (-40 1085);
PAINT MONO (-40 1085);
DISPLAY INVISIBLE (-40 1085);
FORCEPROP 1 LAST HDL_POWER GND
J 0
(-50 1175);
DISPLAY 0.872340 (-50 1175);
PAINT GREEN (-50 1175);
DISPLAY INVISIBLE (-50 1175);
FORCEPROP 1 LAST SIZE 1B
J 0
(25 975);
DISPLAY 0.872340 (25 975);
PAINT GREEN (25 975);
DISPLAY INVISIBLE (25 975);
FORCEPROP 2 LAST CDS_LIB logical_power
J 0
(-50 1025);
DISPLAY INVISIBLE (-50 1025);
FORCEPROP 1 LAST PATH I49
J 0
(25 1025);
DISPLAY 0.872340 (25 1025);
PAINT AQUA (25 1025);
DISPLAY INVISIBLE (25 1025);
FORCEADD Q_RES..2
(-2325 -2350);
FORCEPROP 1 LAST PART_NUMBER CS21002FB06
J 0
(-2285 -2475);
DISPLAY 0.638298 (-2285 -2475);
DISPLAY INVISIBLE (-2285 -2475);
FORCEPROP 1 LAST PACK_TYPE 0402LF
J 0
(-2285 -2475);
DISPLAY 0.638298 (-2285 -2475);
FORCEPROP 1 LAST MATERIAL CHIP
J 0
(-2285 -2425);
DISPLAY 0.638298 (-2285 -2425);
FORCEPROP 1 LAST WATTAGE 1/16W
J 0
(-2285 -2375);
DISPLAY 0.638298 (-2285 -2375);
FORCEPROP 1 LAST TOLERANCE 1%
J 0
(-2280 -2325);
DISPLAY 0.638298 (-2280 -2325);
FORCEPROP 1 LAST VALUE 1K
J 0
(-2280 -2275);
DISPLAY 0.638298 (-2280 -2275);
FORCEPROP 1 LAST LOCATION R3136
J 0
(-2280 -2225);
DISPLAY 0.978723 (-2280 -2225);
FORCEPROP 1 LASTPIN (-2325 -2250) $PN 1
J 0
(-2320 -2288);
DISPLAY 0.787234 (-2320 -2288);
PAINT MONO (-2320 -2288);
FORCEPROP 1 LASTPIN (-2325 -2450) $PN 2
J 0
(-2320 -2440);
DISPLAY 0.787234 (-2320 -2440);
PAINT MONO (-2320 -2440);
FORCEPROP 2 LAST CDS_LIB pure_quanta
J 0
(-2325 -2350);
DISPLAY INVISIBLE (-2325 -2350);
FORCEPROP 1 LAST PATH I5
J 0
(-2275 -2175);
DISPLAY 0.978723 (-2275 -2175);
PAINT WHITE (-2275 -2175);
DISPLAY INVISIBLE (-2275 -2175);
FORCEPROP 0 LAST $SEC 1
J 0
(-2275 -2175);
DISPLAY 0.680851 (-2275 -2175);
PAINT MONO (-2275 -2175);
DISPLAY INVISIBLE (-2275 -2175);
FORCEPROP 0 LAST CDS_SEC 1
J 0
(-2275 -2175);
DISPLAY 1.021277 (-2275 -2175);
DISPLAY INVISIBLE (-2275 -2175);
FORCEADD Q_RES..2
(-50 1550);
FORCEPROP 1 LAST PART_NUMBER CS27152FB03
J 0
(0 1500);
DISPLAY 0.404255 (0 1500);
DISPLAY INVISIBLE (0 1500);
FORCEPROP 1 LAST PACK_TYPE 0402LF
J 0
(0 1475);
DISPLAY 0.404255 (0 1475);
FORCEPROP 1 LAST MATERIAL CHIP
J 0
(0 1525);
DISPLAY 0.404255 (0 1525);
FORCEPROP 1 LAST WATTAGE 1/16W
J 0
(0 1550);
DISPLAY 0.404255 (0 1550);
FORCEPROP 1 LAST TOLERANCE 1%
J 0
(0 1575);
DISPLAY 0.404255 (0 1575);
FORCEPROP 1 LAST VALUE 7.15K
J 0
(0 1600);
DISPLAY 0.404255 (0 1600);
FORCEPROP 2 LAST ROOM NIC1_P3V3_BOM1
J 0
(0 1675);
DISPLAY 0.510638 (0 1675);
FORCEPROP 1 LAST LOCATION PR3829
J 0
(0 1625);
DISPLAY 0.638298 (0 1625);
FORCEPROP 1 LASTPIN (-50 1650) $PN 1
J 0
(-45 1612);
DISPLAY 0.787234 (-45 1612);
PAINT MONO (-45 1612);
FORCEPROP 1 LASTPIN (-50 1450) $PN 2
J 0
(-45 1460);
DISPLAY 0.787234 (-45 1460);
PAINT MONO (-45 1460);
FORCEPROP 1 LAST PATH I50
J 0
(0 1725);
DISPLAY 0.978723 (0 1725);
PAINT WHITE (0 1725);
DISPLAY INVISIBLE (0 1725);
FORCEPROP 2 LAST CDS_LIB pure_quanta
J 0
(-50 1550);
DISPLAY INVISIBLE (-50 1550);
FORCEPROP 0 LAST $SEC 1
J 0
(0 1675);
DISPLAY 0.680851 (0 1675);
PAINT MONO (0 1675);
DISPLAY INVISIBLE (0 1675);
FORCEPROP 0 LAST CDS_SEC 1
J 0
(0 1675);
DISPLAY 1.021277 (0 1675);
DISPLAY INVISIBLE (0 1675);
FORCEADD GND..1
(-400 2250);
FORCEPROP 3 LASTPIN (-400 2300) SIG_NAME GND\g
J 0
(-390 2310);
DISPLAY 0.659574 (-390 2310);
PAINT MONO (-390 2310);
DISPLAY INVISIBLE (-390 2310);
FORCEPROP 1 LAST HDL_POWER GND
J 0
(-400 2400);
DISPLAY 0.872340 (-400 2400);
PAINT GREEN (-400 2400);
DISPLAY INVISIBLE (-400 2400);
FORCEPROP 1 LAST SIZE 1B
J 0
(-325 2200);
DISPLAY 0.872340 (-325 2200);
PAINT GREEN (-325 2200);
DISPLAY INVISIBLE (-325 2200);
FORCEPROP 2 LAST CDS_LIB logical_power
J 0
(-400 2250);
DISPLAY INVISIBLE (-400 2250);
FORCEPROP 1 LAST PATH I51
J 0
(-325 2250);
DISPLAY 0.872340 (-325 2250);
PAINT AQUA (-325 2250);
DISPLAY INVISIBLE (-325 2250);
FORCEADD Q_CAP..1
(-400 2525);
FORCEPROP 1 LAST PART_NUMBER CH5104KEB02
J 0
(-350 2475);
DISPLAY 0.510638 (-350 2475);
DISPLAY INVISIBLE (-350 2475);
FORCEPROP 1 LAST VOLTAGE 25V
J 0
(-350 2550);
DISPLAY 0.510638 (-350 2550);
FORCEPROP 1 LAST MATERIAL X6S
J 0
(-350 2525);
DISPLAY 0.510638 (-350 2525);
FORCEPROP 1 LAST VALUE 1UF
J 0
(-350 2575);
DISPLAY 0.510638 (-350 2575);
FORCEPROP 1 LAST PACK_TYPE C0402
J 0
(-350 2500);
DISPLAY 0.510638 (-350 2500);
FORCEPROP 1 LAST LOCATION PC2140
J 0
(-350 2600);
DISPLAY 0.638298 (-350 2600);
FORCEPROP 1 LAST TOLERANCE 10%
J 0
(-350 2475);
DISPLAY 0.638298 (-350 2475);
DISPLAY INVISIBLE (-350 2475);
FORCEPROP 2 LAST CDS_LIB pure_quanta
J 0
(-400 2525);
DISPLAY INVISIBLE (-400 2525);
FORCEPROP 1 LAST PATH I52
J 0
(-350 2675);
DISPLAY 0.978723 (-350 2675);
PAINT WHITE (-350 2675);
DISPLAY INVISIBLE (-350 2675);
FORCEPROP 0 LAST $SEC 1
J 0
(-345 2667);
DISPLAY INVISIBLE (-345 2667);
FORCEPROP 0 LAST CDS_SEC 1
J 0
(-345 2667);
DISPLAY INVISIBLE (-345 2667);
FORCEPROP 1 LASTPIN (-400 2625) $PN 1
J 0
(-390 2605);
DISPLAY 0.787234 (-390 2605);
PAINT MONO (-390 2605);
DISPLAY INVISIBLE (-390 2605);
FORCEPROP 1 LASTPIN (-400 2425) $PN 2
J 0
(-390 2405);
DISPLAY 0.787234 (-390 2405);
PAINT MONO (-390 2405);
DISPLAY INVISIBLE (-390 2405);
FORCEADD Q_RES..2
(-50 2275);
FORCEPROP 1 LAST PART_NUMBER CS32552FB06
J 0
(0 2225);
DISPLAY 0.404255 (0 2225);
DISPLAY INVISIBLE (0 2225);
FORCEPROP 1 LAST PACK_TYPE 0402LF
J 0
(0 2200);
DISPLAY 0.404255 (0 2200);
FORCEPROP 1 LAST MATERIAL CHIP
J 0
(0 2250);
DISPLAY 0.404255 (0 2250);
FORCEPROP 1 LAST WATTAGE 1/16W
J 0
(0 2275);
DISPLAY 0.404255 (0 2275);
FORCEPROP 1 LAST TOLERANCE 1%
J 0
(0 2300);
DISPLAY 0.404255 (0 2300);
FORCEPROP 1 LAST VALUE 25.5K
J 0
(0 2325);
DISPLAY 0.404255 (0 2325);
FORCEPROP 2 LAST ROOM NIC1_P3V3_BOM1
J 0
(0 2400);
DISPLAY 0.404255 (0 2400);
FORCEPROP 1 LAST LOCATION PR3795
J 0
(0 2350);
DISPLAY 0.638298 (0 2350);
FORCEPROP 1 LASTPIN (-50 2375) $PN 1
J 0
(-45 2337);
DISPLAY 0.787234 (-45 2337);
PAINT MONO (-45 2337);
FORCEPROP 1 LASTPIN (-50 2175) $PN 2
J 0
(-45 2185);
DISPLAY 0.787234 (-45 2185);
PAINT MONO (-45 2185);
FORCEPROP 1 LAST PATH I53
J 0
(0 2450);
DISPLAY 0.978723 (0 2450);
PAINT WHITE (0 2450);
DISPLAY INVISIBLE (0 2450);
FORCEPROP 2 LAST CDS_LIB pure_quanta
J 0
(-50 2275);
DISPLAY INVISIBLE (-50 2275);
FORCEPROP 0 LAST $SEC 1
J 0
(0 2400);
DISPLAY 0.680851 (0 2400);
PAINT MONO (0 2400);
DISPLAY INVISIBLE (0 2400);
FORCEPROP 0 LAST CDS_SEC 1
J 0
(0 2400);
DISPLAY 1.021277 (0 2400);
DISPLAY INVISIBLE (0 2400);
FORCEADD UNIVERSAL_POWER..1
(-400 2875);
FORCEPROP 3 LASTPIN (-400 2825) SIG_NAME P3V3_AUX\g
J 0
(-390 2835);
DISPLAY 0.659574 (-390 2835);
PAINT MONO (-390 2835);
DISPLAY INVISIBLE (-390 2835);
FORCEPROP 1 LAST HDL_POWER P3V3_AUX
J 1
(-400 2925);
DISPLAY 0.872340 (-400 2925);
PAINT GREEN (-400 2925);
FORCEPROP 2 LAST CDS_LIB logical_power
J 0
(-400 2875);
DISPLAY INVISIBLE (-400 2875);
FORCEPROP 1 LAST PATH I54
J 0
(-350 2900);
DISPLAY 0.872340 (-350 2900);
PAINT AQUA (-350 2900);
DISPLAY INVISIBLE (-350 2900);
FORCEADD Q_RES..1
(375 -2475);
FORCEPROP 1 LAST PART_NUMBER CS00002JB13
J 0
(300 -2525);
DISPLAY 0.404255 (300 -2525);
DISPLAY INVISIBLE (300 -2525);
FORCEPROP 1 LAST MATERIAL CHIP
J 0
(300 -2550);
DISPLAY 0.404255 (300 -2550);
FORCEPROP 1 LAST TOLERANCE 5%
J 0
(550 -2475);
DISPLAY 0.404255 (550 -2475);
FORCEPROP 1 LAST VALUE 0
J 2
(525 -2475);
DISPLAY 0.404255 (525 -2475);
FORCEPROP 1 LAST WATTAGE 1/16W
J 2
(500 -2550);
DISPLAY 0.404255 (500 -2550);
FORCEPROP 1 LAST PACK_TYPE 0402LF
J 0
(600 -2475);
DISPLAY 0.404255 (600 -2475);
FORCEPROP 1 LAST $LOCATION R4753
J 0
(175 -2475);
DISPLAY 0.638298 (175 -2475);
FORCEPROP 1 LASTPIN (275 -2475) $PN 1
J 0
(287 -2463);
DISPLAY 0.787234 (287 -2463);
PAINT MONO (287 -2463);
FORCEPROP 1 LASTPIN (475 -2475) $PN 2
J 0
(437 -2463);
DISPLAY 0.787234 (437 -2463);
PAINT MONO (437 -2463);
FORCEPROP 2 LAST CDS_LIB pure_quanta
J 0
(375 -2475);
DISPLAY INVISIBLE (375 -2475);
FORCEPROP 1 LAST PATH I55
J 0
(325 -2325);
DISPLAY 0.978723 (325 -2325);
PAINT WHITE (325 -2325);
DISPLAY INVISIBLE (325 -2325);
FORCEPROP 0 LAST CDS_LOCATION R4753
J 0
(225 -2425);
DISPLAY 1.021277 (225 -2425);
DISPLAY INVISIBLE (225 -2425);
FORCEPROP 0 LAST $SEC 1
J 0
(225 -2425);
DISPLAY 0.680851 (225 -2425);
PAINT MONO (225 -2425);
DISPLAY INVISIBLE (225 -2425);
FORCEPROP 0 LAST CDS_SEC 1
J 0
(225 -2425);
DISPLAY 1.021277 (225 -2425);
DISPLAY INVISIBLE (225 -2425);
FORCEADD Q_RES..1
(425 -2150);
FORCEPROP 1 LAST PART_NUMBER CS00002JB13
J 0
(350 -2200);
DISPLAY 0.404255 (350 -2200);
DISPLAY INVISIBLE (350 -2200);
FORCEPROP 1 LAST TOLERANCE 5%
J 0
(600 -2150);
DISPLAY 0.404255 (600 -2150);
FORCEPROP 1 LAST PACK_TYPE 0402LF
J 0
(650 -2150);
DISPLAY 0.404255 (650 -2150);
FORCEPROP 1 LAST WATTAGE 1/16W
J 2
(550 -2225);
DISPLAY 0.404255 (550 -2225);
FORCEPROP 1 LAST MATERIAL CHIP
J 0
(350 -2225);
DISPLAY 0.404255 (350 -2225);
FORCEPROP 1 LAST VALUE 0
J 2
(575 -2150);
DISPLAY 0.404255 (575 -2150);
FORCEPROP 1 LAST $LOCATION R3143
J 0
(225 -2150);
DISPLAY 0.638298 (225 -2150);
FORCEPROP 1 LASTPIN (325 -2150) $PN 1
J 0
(337 -2138);
DISPLAY 0.787234 (337 -2138);
FORCEPROP 1 LASTPIN (525 -2150) $PN 2
J 0
(487 -2138);
DISPLAY 0.787234 (487 -2138);
FORCEPROP 2 LAST CDS_LIB pure_quanta
J 0
(425 -2150);
PAINT MONO (425 -2150);
DISPLAY INVISIBLE (425 -2150);
FORCEPROP 1 LAST PATH I56
J 0
(375 -2000);
DISPLAY 0.978723 (375 -2000);
PAINT WHITE (375 -2000);
DISPLAY INVISIBLE (375 -2000);
FORCEPROP 2 LAST CDS_LOCATION R3143
J 0
(375 -1950);
DISPLAY 1.021277 (375 -1950);
DISPLAY INVISIBLE (375 -1950);
FORCEPROP 2 LAST $SEC 1
J 0
(375 -1950);
DISPLAY 0.680851 (375 -1950);
PAINT MONO (375 -1950);
DISPLAY INVISIBLE (375 -1950);
FORCEPROP 2 LAST CDS_SEC 1
J 0
(375 -1950);
DISPLAY 1.021277 (375 -1950);
DISPLAY INVISIBLE (375 -1950);
FORCEADD Q_RES..1
(400 -2300);
FORCEPROP 1 LAST PART_NUMBER CS00002JB13
J 0
(325 -2350);
DISPLAY 0.404255 (325 -2350);
DISPLAY INVISIBLE (325 -2350);
FORCEPROP 1 LAST TOLERANCE 5%
J 0
(575 -2300);
DISPLAY 0.404255 (575 -2300);
FORCEPROP 1 LAST PACK_TYPE 0402LF
J 0
(625 -2300);
DISPLAY 0.404255 (625 -2300);
FORCEPROP 1 LAST VALUE 0
J 2
(550 -2300);
DISPLAY 0.404255 (550 -2300);
FORCEPROP 1 LAST MATERIAL CHIP
J 0
(325 -2375);
DISPLAY 0.404255 (325 -2375);
FORCEPROP 1 LAST WATTAGE 1/16W
J 2
(525 -2375);
DISPLAY 0.404255 (525 -2375);
FORCEPROP 1 LAST $LOCATION R3142
J 0
(200 -2300);
DISPLAY 0.638298 (200 -2300);
FORCEPROP 1 LASTPIN (300 -2300) $PN 1
J 0
(312 -2288);
DISPLAY 0.787234 (312 -2288);
FORCEPROP 1 LASTPIN (500 -2300) $PN 2
J 0
(462 -2288);
DISPLAY 0.787234 (462 -2288);
FORCEPROP 2 LAST CDS_LIB pure_quanta
J 0
(400 -2300);
PAINT MONO (400 -2300);
DISPLAY INVISIBLE (400 -2300);
FORCEPROP 1 LAST PATH I57
J 0
(350 -2150);
DISPLAY 0.978723 (350 -2150);
PAINT WHITE (350 -2150);
DISPLAY INVISIBLE (350 -2150);
FORCEPROP 2 LAST CDS_LOCATION R3142
J 0
(350 -2100);
DISPLAY 1.021277 (350 -2100);
DISPLAY INVISIBLE (350 -2100);
FORCEPROP 2 LAST $SEC 1
J 0
(350 -2100);
DISPLAY 0.680851 (350 -2100);
PAINT MONO (350 -2100);
DISPLAY INVISIBLE (350 -2100);
FORCEPROP 2 LAST CDS_SEC 1
J 0
(350 -2100);
DISPLAY 1.021277 (350 -2100);
DISPLAY INVISIBLE (350 -2100);
FORCEADD GND..1
(675 -1325);
FORCEPROP 3 LASTPIN (675 -1275) SIG_NAME GND\g
J 0
(685 -1265);
DISPLAY 0.659574 (685 -1265);
PAINT MONO (685 -1265);
DISPLAY INVISIBLE (685 -1265);
FORCEPROP 1 LAST HDL_POWER GND
J 0
(675 -1175);
DISPLAY 0.872340 (675 -1175);
PAINT GREEN (675 -1175);
DISPLAY INVISIBLE (675 -1175);
FORCEPROP 1 LAST SIZE 1B
J 0
(750 -1375);
DISPLAY 0.872340 (750 -1375);
PAINT GREEN (750 -1375);
DISPLAY INVISIBLE (750 -1375);
FORCEPROP 2 LAST CDS_LIB logical_power
J 0
(675 -1325);
DISPLAY INVISIBLE (675 -1325);
FORCEPROP 1 LAST PATH I58
J 0
(750 -1325);
DISPLAY 0.872340 (750 -1325);
PAINT AQUA (750 -1325);
DISPLAY INVISIBLE (750 -1325);
FORCEADD Q_RES..2
(675 -1025);
FORCEPROP 1 LAST PART_NUMBER CS33012FB03
J 0
(725 -1100);
DISPLAY 0.510638 (725 -1100);
DISPLAY INVISIBLE (725 -1100);
FORCEPROP 1 LAST TOLERANCE 1%
J 0
(725 -1025);
DISPLAY 0.510638 (725 -1025);
FORCEPROP 1 LAST MATERIAL EMPTY
J 0
(725 -1075);
DISPLAY 0.510638 (725 -1075);
PAINT RED (725 -1075);
FORCEPROP 1 LAST VALUE 30.1K
J 0
(725 -1000);
DISPLAY 0.510638 (725 -1000);
FORCEPROP 1 LAST WATTAGE 1/16W
J 0
(725 -1050);
DISPLAY 0.510638 (725 -1050);
FORCEPROP 1 LAST PACK_TYPE 0402LF
J 0
(725 -1125);
DISPLAY 0.510638 (725 -1125);
FORCEPROP 2 LAST ROOM NIC1_P12V_MAM_MAM_BOM1
J 0
(725 -925);
DISPLAY 1.021277 (725 -925);
FORCEPROP 1 LAST LOCATION PR3821
J 0
(725 -975);
DISPLAY 0.638298 (725 -975);
FORCEPROP 1 LASTPIN (675 -925) $PN 1
J 0
(680 -963);
DISPLAY 0.787234 (680 -963);
PAINT MONO (680 -963);
FORCEPROP 1 LASTPIN (675 -1125) $PN 2
J 0
(680 -1115);
DISPLAY 0.787234 (680 -1115);
PAINT MONO (680 -1115);
FORCEPROP 1 LAST PATH I59
J 0
(725 -850);
DISPLAY 0.978723 (725 -850);
PAINT WHITE (725 -850);
DISPLAY INVISIBLE (725 -850);
FORCEPROP 2 LAST CDS_LIB pure_quanta
J 0
(675 -1025);
DISPLAY INVISIBLE (675 -1025);
FORCEPROP 2 LAST ROOM1 NIC1_P12V_MAM_TIC_BOM2
J 0
(725 -875);
DISPLAY 1.021277 (725 -875);
DISPLAY INVISIBLE (725 -875);
FORCEPROP 0 LAST $SEC 1
J 0
(725 -875);
DISPLAY 0.680851 (725 -875);
PAINT MONO (725 -875);
DISPLAY INVISIBLE (725 -875);
FORCEPROP 0 LAST CDS_SEC 1
J 0
(725 -900);
DISPLAY INVISIBLE (725 -900);
FORCEADD Q_RES..1
(-3900 -1000);
FORCEPROP 1 LAST PART_NUMBER CS00002JB13
J 0
(-4200 -1075);
DISPLAY 0.595745 (-4200 -1075);
DISPLAY INVISIBLE (-4200 -1075);
FORCEPROP 1 LAST MATERIAL EMPTY
J 0
(-4025 -1125);
DISPLAY 0.595745 (-4025 -1125);
PAINT RED (-4025 -1125);
FORCEPROP 1 LAST PACK_TYPE 0402LF
J 0
(-3825 -1075);
DISPLAY 0.595745 (-3825 -1075);
FORCEPROP 1 LAST WATTAGE 1/16W
J 2
(-3700 -1125);
DISPLAY 0.595745 (-3700 -1125);
FORCEPROP 1 LAST VALUE 0
J 2
(-3750 -1000);
DISPLAY 0.595745 (-3750 -1000);
FORCEPROP 1 LAST TOLERANCE 5%
J 0
(-3725 -1000);
DISPLAY 0.595745 (-3725 -1000);
FORCEPROP 2 LAST ROOM NIC1_P12V_MAM_MAM_BOM1
J 0
(-3725 -950);
DISPLAY 1.021277 (-3725 -950);
FORCEPROP 1 LAST $LOCATION R4059
J 0
(-4050 -1000);
DISPLAY 0.638298 (-4050 -1000);
FORCEPROP 1 LAST PATH I6
J 0
(-3950 -850);
DISPLAY 0.978723 (-3950 -850);
PAINT WHITE (-3950 -850);
DISPLAY INVISIBLE (-3950 -850);
FORCEPROP 2 LAST CDS_LIB pure_quanta
J 0
(-3900 -1000);
DISPLAY INVISIBLE (-3900 -1000);
FORCEPROP 2 LAST ROOM1 NIC1_P12V_MAM_TIC_BOM2
J 0
(-3725 -900);
DISPLAY 1.021277 (-3725 -900);
DISPLAY INVISIBLE (-3725 -900);
FORCEPROP 0 LAST CDS_LOCATION R4059
J 0
(-3825 -925);
DISPLAY INVISIBLE (-3825 -925);
FORCEPROP 0 LAST $SEC 1
J 0
(-3825 -925);
DISPLAY INVISIBLE (-3825 -925);
FORCEPROP 0 LAST CDS_SEC 1
J 0
(-3825 -925);
DISPLAY INVISIBLE (-3825 -925);
FORCEPROP 1 LASTPIN (-4000 -1000) $PN 1
J 0
(-3988 -988);
DISPLAY 0.787234 (-3988 -988);
PAINT MONO (-3988 -988);
DISPLAY INVISIBLE (-3988 -988);
FORCEPROP 1 LASTPIN (-3800 -1000) $PN 2
J 0
(-3838 -988);
DISPLAY 0.787234 (-3838 -988);
PAINT MONO (-3838 -988);
DISPLAY INVISIBLE (-3838 -988);
FORCEADD GND..1
(150 -600);
FORCEPROP 3 LASTPIN (150 -550) SIG_NAME GND\g
J 0
(160 -540);
DISPLAY 0.659574 (160 -540);
PAINT MONO (160 -540);
DISPLAY INVISIBLE (160 -540);
FORCEPROP 1 LAST HDL_POWER GND
J 0
(150 -450);
DISPLAY 0.872340 (150 -450);
PAINT GREEN (150 -450);
DISPLAY INVISIBLE (150 -450);
FORCEPROP 2 LAST CDS_LIB logical_power
J 0
(150 -600);
DISPLAY INVISIBLE (150 -600);
FORCEPROP 1 LAST SIZE 1B
J 0
(225 -650);
DISPLAY 0.872340 (225 -650);
PAINT GREEN (225 -650);
DISPLAY INVISIBLE (225 -650);
FORCEPROP 1 LAST PATH I60
J 0
(225 -600);
DISPLAY 0.872340 (225 -600);
PAINT AQUA (225 -600);
DISPLAY INVISIBLE (225 -600);
FORCEADD Q_CAP..1
(150 -225);
FORCEPROP 1 LAST PART_NUMBER CH5104KEB02
J 0
(200 -325);
DISPLAY 0.510638 (200 -325);
DISPLAY INVISIBLE (200 -325);
FORCEPROP 1 LAST VALUE 1UF
J 0
(200 -225);
DISPLAY 0.510638 (200 -225);
FORCEPROP 1 LAST MATERIAL EMPTY
J 0
(200 -250);
DISPLAY 0.510638 (200 -250);
PAINT RED (200 -250);
FORCEPROP 1 LAST VOLTAGE 25V
J 0
(200 -275);
DISPLAY 0.510638 (200 -275);
FORCEPROP 1 LAST PACK_TYPE C0402
J 0
(200 -300);
DISPLAY 0.510638 (200 -300);
FORCEPROP 2 LAST ROOM NIC1_P12V_MAM_MAM_BOM1
J 0
(200 -150);
DISPLAY 1.021277 (200 -150);
FORCEPROP 1 LAST LOCATION PC2098
J 0
(200 -200);
DISPLAY 0.638298 (200 -200);
FORCEPROP 1 LASTPIN (150 -125) $PN 1
J 0
(160 -145);
DISPLAY 0.787234 (160 -145);
PAINT MONO (160 -145);
FORCEPROP 1 LASTPIN (150 -325) $PN 2
J 0
(160 -345);
DISPLAY 0.787234 (160 -345);
PAINT MONO (160 -345);
FORCEPROP 1 LAST PATH I61
J 0
(200 -75);
DISPLAY 0.978723 (200 -75);
PAINT WHITE (200 -75);
DISPLAY INVISIBLE (200 -75);
FORCEPROP 1 LAST TOLERANCE 10%
J 0
(200 -275);
DISPLAY 0.638298 (200 -275);
DISPLAY INVISIBLE (200 -275);
FORCEPROP 2 LAST CDS_LIB pure_quanta
J 0
(150 -225);
DISPLAY INVISIBLE (150 -225);
FORCEPROP 2 LAST ROOM1 NIC1_P12V_MAM_TIC_BOM2
J 0
(200 -100);
DISPLAY 1.021277 (200 -100);
DISPLAY INVISIBLE (200 -100);
FORCEPROP 0 LAST $SEC 1
J 0
(200 -150);
DISPLAY 0.680851 (200 -150);
PAINT MONO (200 -150);
DISPLAY INVISIBLE (200 -150);
FORCEPROP 0 LAST CDS_SEC 1
J 0
(200 -150);
DISPLAY 1.021277 (200 -150);
DISPLAY INVISIBLE (200 -150);
FORCEADD Q_CAP..1
R 1
(375 -525);
FORCEPROP 1 LAST PART_NUMBER CH5104KEB02
J 0
(425 -575);
DISPLAY 0.510638 (425 -575);
DISPLAY INVISIBLE (425 -575);
FORCEPROP 1 LAST VOLTAGE 25V
J 0
(525 -475);
DISPLAY 0.510638 (525 -475);
FORCEPROP 1 LAST VALUE 1UF
J 0
(350 -475);
DISPLAY 0.510638 (350 -475);
FORCEPROP 1 LAST PACK_TYPE C0402
J 0
(200 -575);
DISPLAY 0.510638 (200 -575);
FORCEPROP 2 LAST ROOM NIC1_P12V_MAM_MAM_BOM1
J 0
(200 -425);
DISPLAY 1.021277 (200 -425);
FORCEPROP 1 LAST LOCATION PC2146
J 0
(200 -475);
DISPLAY 0.638298 (200 -475);
FORCEPROP 1 LASTPIN (275 -525) $PN 1
R 1
J 0
(295 -515);
DISPLAY 0.787234 (295 -515);
PAINT MONO (295 -515);
FORCEPROP 1 LASTPIN (475 -525) $PN 2
R 1
J 0
(495 -515);
DISPLAY 0.787234 (495 -515);
PAINT MONO (495 -515);
FORCEPROP 1 LAST PATH I62
R 1
J 0
(225 -475);
DISPLAY 0.978723 (225 -475);
PAINT WHITE (225 -475);
DISPLAY INVISIBLE (225 -475);
FORCEPROP 1 LAST MATERIAL EMPTY
R 1
J 0
(375 -475);
DISPLAY 0.638298 (375 -475);
DISPLAY INVISIBLE (375 -475);
FORCEPROP 1 LAST TOLERANCE 10%
R 1
J 0
(425 -475);
DISPLAY 0.638298 (425 -475);
DISPLAY INVISIBLE (425 -475);
FORCEPROP 2 LAST CDS_LIB pure_quanta
J 0
(375 -525);
DISPLAY INVISIBLE (375 -525);
FORCEPROP 2 LAST ROOM1 NIC1_P12V_MAM_TIC_BOM2
J 0
(200 -375);
DISPLAY 1.021277 (200 -375);
DISPLAY INVISIBLE (200 -375);
FORCEPROP 0 LAST $SEC 1
R 1
J 0
(200 -425);
DISPLAY 0.680851 (200 -425);
PAINT MONO (200 -425);
DISPLAY INVISIBLE (200 -425);
FORCEPROP 0 LAST CDS_SEC 1
R 1
J 0
(200 -425);
DISPLAY 1.021277 (200 -425);
DISPLAY INVISIBLE (200 -425);
FORCEADD MAX15090BEWIT..1
(1425 -525);
FORCEPROP 1 LAST PART_NUMBER AL015080B00
J 0
(1172 119);
DISPLAY 0.723404 (1172 119);
PAINT GREEN (1172 119);
DISPLAY INVISIBLE (1172 119);
FORCEPROP 2 LAST PART_TYPE SMLF
J 0
(1175 300);
DISPLAY 1.021277 (1175 300);
FORCEPROP 2 LAST VALUE MAX15090BEWI+T
J 0
(1175 250);
DISPLAY 1.021277 (1175 250);
FORCEPROP 1 LAST MATERIAL EMPTY
J 0
(1172 30);
DISPLAY 0.723404 (1172 30);
PAINT RED (1172 30);
FORCEPROP 2 LAST ROOM NIC1_P12V_MAM_MAM_BOM1
J 0
(1175 350);
DISPLAY 1.021277 (1175 350);
FORCEPROP 1 LAST LOCATION PU201
J 0
(1172 203);
DISPLAY 0.723404 (1172 203);
PAINT GREEN (1172 203);
FORCEPROP 0 LASTPIN (1025 -825) $PN B1
J 2
(1015 -815);
DISPLAY 0.680851 (1015 -815);
PAINT MONO (1015 -815);
FORCEPROP 0 LASTPIN (1825 -825) $PN A7
J 0
(1835 -815);
DISPLAY 0.680851 (1835 -815);
PAINT MONO (1835 -815);
FORCEPROP 0 LASTPIN (1025 -925) $PN B7
J 2
(1015 -915);
DISPLAY 0.680851 (1015 -915);
PAINT MONO (1015 -915);
FORCEPROP 0 LASTPIN (1825 -625) $PN C7
J 0
(1835 -615);
DISPLAY 0.680851 (1835 -615);
PAINT MONO (1835 -615);
FORCEPROP 0 LASTPIN (1825 -425) $PN A6
J 0
(1835 -415);
DISPLAY 0.680851 (1835 -415);
PAINT MONO (1835 -415);
FORCEPROP 0 LASTPIN (1825 -925) $PN B2
J 0
(1835 -915);
DISPLAY 0.680851 (1835 -915);
PAINT MONO (1835 -915);
FORCEPROP 0 LASTPIN (1825 -975) $PN C1
J 0
(1835 -965);
DISPLAY 0.680851 (1835 -965);
PAINT MONO (1835 -965);
FORCEPROP 0 LASTPIN (1825 -1025) $PN C2
J 0
(1835 -1015);
DISPLAY 0.680851 (1835 -1015);
PAINT MONO (1835 -1015);
FORCEPROP 0 LASTPIN (1025 -25) $PN A3
J 2
(1015 -15);
DISPLAY 0.680851 (1015 -15);
PAINT MONO (1015 -15);
FORCEPROP 0 LASTPIN (1025 -75) $PN A5
J 2
(1015 -65);
DISPLAY 0.680851 (1015 -65);
PAINT MONO (1015 -65);
FORCEPROP 0 LASTPIN (1025 -125) $PN B3
J 2
(1015 -115);
DISPLAY 0.680851 (1015 -115);
PAINT MONO (1015 -115);
FORCEPROP 0 LASTPIN (1025 -175) $PN B5
J 2
(1015 -165);
DISPLAY 0.680851 (1015 -165);
PAINT MONO (1015 -165);
FORCEPROP 0 LASTPIN (1025 -225) $PN C3
J 2
(1015 -215);
DISPLAY 0.680851 (1015 -215);
PAINT MONO (1015 -215);
FORCEPROP 0 LASTPIN (1025 -275) $PN C5
J 2
(1015 -265);
DISPLAY 0.680851 (1015 -265);
PAINT MONO (1015 -265);
FORCEPROP 0 LASTPIN (1025 -325) $PN D5
J 2
(1015 -315);
DISPLAY 0.680851 (1015 -315);
PAINT MONO (1015 -315);
FORCEPROP 0 LASTPIN (1825 -725) $PN A1
J 0
(1835 -715);
DISPLAY 0.680851 (1835 -715);
PAINT MONO (1835 -715);
FORCEPROP 0 LASTPIN (1825 -25) $PN A4
J 0
(1835 -15);
DISPLAY 0.680851 (1835 -15);
PAINT MONO (1835 -15);
FORCEPROP 0 LASTPIN (1825 -75) $PN B4
J 0
(1835 -65);
DISPLAY 0.680851 (1835 -65);
PAINT MONO (1835 -65);
FORCEPROP 0 LASTPIN (1825 -125) $PN B6
J 0
(1835 -115);
DISPLAY 0.680851 (1835 -115);
PAINT MONO (1835 -115);
FORCEPROP 0 LASTPIN (1825 -175) $PN C4
J 0
(1835 -165);
DISPLAY 0.680851 (1835 -165);
PAINT MONO (1835 -165);
FORCEPROP 0 LASTPIN (1825 -225) $PN C6
J 0
(1835 -215);
DISPLAY 0.680851 (1835 -215);
PAINT MONO (1835 -215);
FORCEPROP 0 LASTPIN (1825 -275) $PN D4
J 0
(1835 -265);
DISPLAY 0.680851 (1835 -265);
PAINT MONO (1835 -265);
FORCEPROP 0 LASTPIN (1825 -325) $PN D6
J 0
(1835 -315);
DISPLAY 0.680851 (1835 -315);
PAINT MONO (1835 -315);
FORCEPROP 0 LASTPIN (1025 -725) $PN D3
J 2
(1015 -715);
DISPLAY 0.680851 (1015 -715);
PAINT MONO (1015 -715);
FORCEPROP 0 LASTPIN (1825 -525) $PN D7
J 0
(1835 -515);
DISPLAY 0.680851 (1835 -515);
PAINT MONO (1835 -515);
FORCEPROP 0 LASTPIN (1025 -525) $PN D1
J 2
(1015 -515);
DISPLAY 0.680851 (1015 -515);
PAINT MONO (1015 -515);
FORCEPROP 0 LASTPIN (1025 -625) $PN D2
J 2
(1015 -615);
DISPLAY 0.680851 (1015 -615);
PAINT MONO (1015 -615);
FORCEPROP 0 LASTPIN (1025 -425) $PN A2
J 2
(1015 -415);
DISPLAY 0.680851 (1015 -415);
PAINT MONO (1015 -415);
FORCEPROP 1 LAST PATH I63
J 0
(1675 -1075);
DISPLAY 0.723404 (1675 -1075);
PAINT GREEN (1675 -1075);
DISPLAY INVISIBLE (1675 -1075);
FORCEPROP 1 LAST CDS_LMAN_SYM_OUTLINE -250,550,250,-550
J 0
(1425 -525);
DISPLAY 0.468085 (1425 -525);
PAINT GREEN (1425 -525);
DISPLAY INVISIBLE (1425 -525);
FORCEPROP 1 LAST PIN_NAMES_ROTATE True
J 0
(1425 -525);
DISPLAY 0.489362 (1425 -525);
PAINT GREEN (1425 -525);
DISPLAY INVISIBLE (1425 -525);
FORCEPROP 2 LAST CDS_LIB pure_quanta
J 0
(1425 -525);
DISPLAY INVISIBLE (1425 -525);
FORCEPROP 2 LAST ROOM1 NIC1_P12V_MAM_TIC_BOM2
J 0
(1175 400);
DISPLAY 1.021277 (1175 400);
DISPLAY INVISIBLE (1175 400);
FORCEPROP 0 LAST $SEC 1
J 0
(1175 350);
DISPLAY 0.680851 (1175 350);
PAINT MONO (1175 350);
DISPLAY INVISIBLE (1175 350);
FORCEPROP 0 LAST CDS_SEC 1
J 0
(1175 350);
DISPLAY 1.021277 (1175 350);
DISPLAY INVISIBLE (1175 350);
FORCEADD Q_RES..2
(1675 -1875);
FORCEPROP 1 LAST PART_NUMBER CS31002FB08
J 0
(1715 -2000);
DISPLAY 0.510638 (1715 -2000);
DISPLAY INVISIBLE (1715 -2000);
FORCEPROP 1 LAST TOLERANCE 1%
J 0
(1720 -1850);
DISPLAY 0.510638 (1720 -1850);
FORCEPROP 1 LAST VALUE 10K
J 0
(1720 -1800);
DISPLAY 0.510638 (1720 -1800);
FORCEPROP 1 LAST MATERIAL CHIP
J 0
(1715 -1950);
DISPLAY 0.510638 (1715 -1950);
FORCEPROP 1 LAST WATTAGE 1/16W
J 0
(1715 -1900);
DISPLAY 0.510638 (1715 -1900);
FORCEPROP 1 LAST PACK_TYPE 0402LF
J 0
(1715 -2000);
DISPLAY 0.510638 (1715 -2000);
FORCEPROP 1 LAST $LOCATION R3145
J 0
(1720 -1750);
DISPLAY 0.978723 (1720 -1750);
FORCEPROP 1 LASTPIN (1675 -1775) $PN 1
J 0
(1680 -1813);
DISPLAY 0.787234 (1680 -1813);
FORCEPROP 1 LASTPIN (1675 -1975) $PN 2
J 0
(1680 -1965);
DISPLAY 0.787234 (1680 -1965);
FORCEPROP 2 LAST CDS_LIB pure_quanta
J 0
(1675 -1875);
PAINT MONO (1675 -1875);
DISPLAY INVISIBLE (1675 -1875);
FORCEPROP 1 LAST PATH I64
J 0
(1725 -1700);
DISPLAY 0.978723 (1725 -1700);
PAINT WHITE (1725 -1700);
DISPLAY INVISIBLE (1725 -1700);
FORCEPROP 2 LAST CDS_LOCATION R3145
J 0
(1725 -1650);
DISPLAY 1.021277 (1725 -1650);
DISPLAY INVISIBLE (1725 -1650);
FORCEPROP 2 LAST $SEC 1
J 0
(1725 -1650);
DISPLAY 0.680851 (1725 -1650);
PAINT MONO (1725 -1650);
DISPLAY INVISIBLE (1725 -1650);
FORCEPROP 2 LAST CDS_SEC 1
J 0
(1725 -1650);
DISPLAY 1.021277 (1725 -1650);
DISPLAY INVISIBLE (1725 -1650);
FORCEADD UNIVERSAL_POWER..1
(1675 -1575);
FORCEPROP 3 LASTPIN (1675 -1625) SIG_NAME P3V3_AUX\g
J 0
(1685 -1615);
DISPLAY 0.659574 (1685 -1615);
PAINT MONO (1685 -1615);
DISPLAY INVISIBLE (1685 -1615);
FORCEPROP 1 LAST HDL_POWER P3V3_AUX
J 1
(1675 -1525);
DISPLAY 0.872340 (1675 -1525);
PAINT GREEN (1675 -1525);
FORCEPROP 2 LAST CDS_LIB logical_power
J 0
(1675 -1575);
PAINT MONO (1675 -1575);
DISPLAY INVISIBLE (1675 -1575);
FORCEPROP 1 LAST PATH I65
J 0
(1725 -1550);
DISPLAY 0.872340 (1725 -1550);
PAINT AQUA (1725 -1550);
DISPLAY INVISIBLE (1725 -1550);
FORCEADD Q_RES..2
(1900 -1875);
FORCEPROP 1 LAST PART_NUMBER CS31002FB08
J 0
(1940 -2050);
DISPLAY 0.510638 (1940 -2050);
DISPLAY INVISIBLE (1940 -2050);
FORCEPROP 1 LAST PACK_TYPE 0402LF
J 0
(1940 -2000);
DISPLAY 0.510638 (1940 -2000);
FORCEPROP 1 LAST VALUE 10K
J 0
(1945 -1800);
DISPLAY 0.510638 (1945 -1800);
FORCEPROP 1 LAST TOLERANCE 1%
J 0
(1945 -1850);
DISPLAY 0.510638 (1945 -1850);
FORCEPROP 1 LAST WATTAGE 1/16W
J 0
(1940 -1900);
DISPLAY 0.510638 (1940 -1900);
FORCEPROP 1 LAST MATERIAL CHIP
J 0
(1940 -1950);
DISPLAY 0.510638 (1940 -1950);
FORCEPROP 1 LAST $LOCATION R3147
J 0
(1945 -1750);
DISPLAY 0.978723 (1945 -1750);
FORCEPROP 1 LASTPIN (1900 -1775) $PN 1
J 0
(1905 -1813);
DISPLAY 0.787234 (1905 -1813);
FORCEPROP 1 LASTPIN (1900 -1975) $PN 2
J 0
(1905 -1965);
DISPLAY 0.787234 (1905 -1965);
FORCEPROP 2 LAST CDS_LIB pure_quanta
J 0
(1900 -1875);
PAINT MONO (1900 -1875);
DISPLAY INVISIBLE (1900 -1875);
FORCEPROP 1 LAST PATH I66
J 0
(1950 -1700);
DISPLAY 0.978723 (1950 -1700);
PAINT WHITE (1950 -1700);
DISPLAY INVISIBLE (1950 -1700);
FORCEPROP 2 LAST CDS_LOCATION R3147
J 0
(1950 -1650);
DISPLAY 1.021277 (1950 -1650);
DISPLAY INVISIBLE (1950 -1650);
FORCEPROP 2 LAST $SEC 1
J 0
(1950 -1650);
DISPLAY 0.680851 (1950 -1650);
PAINT MONO (1950 -1650);
DISPLAY INVISIBLE (1950 -1650);
FORCEPROP 2 LAST CDS_SEC 1
J 0
(1950 -1650);
DISPLAY 1.021277 (1950 -1650);
DISPLAY INVISIBLE (1950 -1650);
FORCEADD OFFPAGE..2
(2750 -2475);
FORCEPROP 2 LAST $XR0 216 
J 0
(2939 -2475);
DISPLAY 0.638298 (2939 -2475);
PAINT MONO (2939 -2475);
FORCEPROP 1 LAST OFFPAGE TRUE
J 0
(3075 -2600);
DISPLAY 0.872340 (3075 -2600);
DISPLAY INVISIBLE (3075 -2600);
FORCEPROP 1 LAST COMMENT_BODY TRUE
J 0
(2705 -2570);
DISPLAY 0.872340 (2705 -2570);
PAINT GREEN (2705 -2570);
DISPLAY INVISIBLE (2705 -2570);
FORCEPROP 2 LAST CDS_LIB standard
J 0
(2750 -2475);
DISPLAY INVISIBLE (2750 -2475);
FORCEPROP 2 LAST PATH I67
J 0
(2950 -2425);
DISPLAY 1.021277 (2950 -2425);
DISPLAY INVISIBLE (2950 -2425);
FORCEADD OFFPAGE..2
(2750 -2300);
FORCEPROP 2 LAST $XR0 164 
J 0
(2939 -2300);
DISPLAY 0.638298 (2939 -2300);
PAINT MONO (2939 -2300);
FORCEPROP 2 LAST CDS_LIB standard
J 0
(2750 -2300);
PAINT MONO (2750 -2300);
DISPLAY INVISIBLE (2750 -2300);
FORCEPROP 1 LAST OFFPAGE TRUE
J 0
(3075 -2425);
DISPLAY 0.872340 (3075 -2425);
DISPLAY INVISIBLE (3075 -2425);
FORCEPROP 1 LAST COMMENT_BODY TRUE
J 0
(2705 -2395);
DISPLAY 0.872340 (2705 -2395);
PAINT GREEN (2705 -2395);
DISPLAY INVISIBLE (2705 -2395);
FORCEPROP 2 LAST PATH I68
J 0
(2950 -2250);
DISPLAY 1.021277 (2950 -2250);
DISPLAY INVISIBLE (2950 -2250);
FORCEADD OFFPAGE..2
(2750 -2150);
FORCEPROP 2 LAST $XR0 164 
J 0
(2939 -2150);
DISPLAY 0.638298 (2939 -2150);
PAINT MONO (2939 -2150);
FORCEPROP 2 LAST CDS_LIB standard
J 0
(2750 -2150);
PAINT MONO (2750 -2150);
DISPLAY INVISIBLE (2750 -2150);
FORCEPROP 1 LAST OFFPAGE TRUE
J 0
(3075 -2275);
DISPLAY 0.872340 (3075 -2275);
DISPLAY INVISIBLE (3075 -2275);
FORCEPROP 1 LAST COMMENT_BODY TRUE
J 0
(2705 -2245);
DISPLAY 0.872340 (2705 -2245);
PAINT GREEN (2705 -2245);
DISPLAY INVISIBLE (2705 -2245);
FORCEPROP 2 LAST PATH I69
J 0
(2950 -2100);
DISPLAY 1.021277 (2950 -2100);
DISPLAY INVISIBLE (2950 -2100);
FORCEADD MOSFET_NCH_DUAL..1
(-3025 -950);
FORCEPROP 1 LAST PART_NUMBER BAM138K0003
J 0
(-2874 -1036);
DISPLAY 0.723404 (-2874 -1036);
PAINT GREEN (-2874 -1036);
DISPLAY INVISIBLE (-2874 -1036);
FORCEPROP 2 LAST PART_TYPE SMLF
J 0
(-2850 -875);
DISPLAY 1.021277 (-2850 -875);
FORCEPROP 1 LAST MATERIAL EMPTY
J 0
(-2874 -1101);
DISPLAY 0.723404 (-2874 -1101);
PAINT RED (-2874 -1101);
FORCEPROP 2 LAST VALUE PJT138K
J 0
(-2850 -925);
DISPLAY 1.021277 (-2850 -925);
FORCEPROP 2 LAST ROOM NIC1_P12V_MAM_MAM_BOM1
J 0
(-2850 -825);
DISPLAY 1.021277 (-2850 -825);
FORCEPROP 1 LAST $LOCATION Q118
J 0
(-2874 -976);
DISPLAY 0.723404 (-2874 -976);
PAINT GREEN (-2874 -976);
FORCEPROP 0 LASTPIN (-2975 -750) $PN 6
R 1
J 0
(-2985 -740);
DISPLAY 0.680851 (-2985 -740);
PAINT MONO (-2985 -740);
FORCEPROP 0 LASTPIN (-3225 -1000) $PN 2
J 2
(-3235 -990);
DISPLAY 0.680851 (-3235 -990);
PAINT MONO (-3235 -990);
FORCEPROP 0 LASTPIN (-2975 -1150) $PN 1
R 1
J 2
(-2985 -1160);
DISPLAY 0.680851 (-2985 -1160);
PAINT MONO (-2985 -1160);
FORCEPROP 1 LAST PATH I7
J 0
(-3025 -950);
DISPLAY 0.723404 (-3025 -950);
PAINT GREEN (-3025 -950);
DISPLAY INVISIBLE (-3025 -950);
FORCEPROP 2 LAST CDS_LIB pure_quanta
J 0
(-3025 -950);
DISPLAY INVISIBLE (-3025 -950);
FORCEPROP 1 LAST CDS_LMAN_SYM_OUTLINE -150,150,150,-150
J 0
(-3025 -950);
DISPLAY 0.468085 (-3025 -950);
PAINT GREEN (-3025 -950);
DISPLAY INVISIBLE (-3025 -950);
FORCEPROP 1 LAST NEEDS_NO_SIZE TRUE
J 0
(-3025 -951);
DISPLAY 0.468085 (-3025 -951);
PAINT GREEN (-3025 -951);
DISPLAY INVISIBLE (-3025 -951);
FORCEPROP 2 LAST ROOM1 NIC1_P12V_MAM_TIC_BOM2
J 0
(-2850 -775);
DISPLAY 1.021277 (-2850 -775);
DISPLAY INVISIBLE (-2850 -775);
FORCEPROP 0 LAST CDS_LOCATION Q118
J 0
(-2850 -825);
DISPLAY 1.021277 (-2850 -825);
DISPLAY INVISIBLE (-2850 -825);
FORCEPROP 0 LAST $SEC 1
J 0
(-2850 -825);
DISPLAY 0.680851 (-2850 -825);
PAINT MONO (-2850 -825);
DISPLAY INVISIBLE (-2850 -825);
FORCEPROP 0 LAST CDS_SEC 1
J 0
(-2850 -825);
DISPLAY 1.021277 (-2850 -825);
DISPLAY INVISIBLE (-2850 -825);
FORCEADD Q_RES..2
(2250 -1900);
FORCEPROP 1 LAST PART_NUMBER CS31002FB08
J 0
(2290 -2075);
DISPLAY 0.510638 (2290 -2075);
DISPLAY INVISIBLE (2290 -2075);
FORCEPROP 1 LAST MATERIAL CHIP
J 0
(2290 -1975);
DISPLAY 0.510638 (2290 -1975);
FORCEPROP 1 LAST WATTAGE 1/16W
J 0
(2290 -1925);
DISPLAY 0.510638 (2290 -1925);
FORCEPROP 1 LAST TOLERANCE 1%
J 0
(2295 -1875);
DISPLAY 0.510638 (2295 -1875);
FORCEPROP 1 LAST VALUE 10K
J 0
(2295 -1825);
DISPLAY 0.510638 (2295 -1825);
FORCEPROP 1 LAST PACK_TYPE 0402LF
J 0
(2290 -2025);
DISPLAY 0.510638 (2290 -2025);
FORCEPROP 1 LAST $LOCATION R4761
J 0
(2295 -1775);
DISPLAY 0.978723 (2295 -1775);
FORCEPROP 1 LASTPIN (2250 -1800) $PN 1
J 0
(2255 -1838);
DISPLAY 0.787234 (2255 -1838);
PAINT MONO (2255 -1838);
FORCEPROP 1 LASTPIN (2250 -2000) $PN 2
J 0
(2255 -1990);
DISPLAY 0.787234 (2255 -1990);
PAINT MONO (2255 -1990);
FORCEPROP 2 LAST CDS_LIB pure_quanta
J 0
(2250 -1900);
DISPLAY INVISIBLE (2250 -1900);
FORCEPROP 1 LAST PATH I70
J 0
(2300 -1725);
DISPLAY 0.978723 (2300 -1725);
PAINT WHITE (2300 -1725);
DISPLAY INVISIBLE (2300 -1725);
FORCEPROP 0 LAST CDS_LOCATION R4761
J 0
(2300 -1725);
DISPLAY 1.021277 (2300 -1725);
DISPLAY INVISIBLE (2300 -1725);
FORCEPROP 0 LAST $SEC 1
J 0
(2300 -1725);
DISPLAY 0.680851 (2300 -1725);
PAINT MONO (2300 -1725);
DISPLAY INVISIBLE (2300 -1725);
FORCEPROP 0 LAST CDS_SEC 1
J 0
(2300 -1725);
DISPLAY 1.021277 (2300 -1725);
DISPLAY INVISIBLE (2300 -1725);
FORCEADD GND..1
(2150 -1200);
FORCEPROP 3 LASTPIN (2150 -1150) SIG_NAME GND\g
J 0
(2160 -1140);
DISPLAY 0.659574 (2160 -1140);
PAINT MONO (2160 -1140);
DISPLAY INVISIBLE (2160 -1140);
FORCEPROP 1 LAST HDL_POWER GND
J 0
(2150 -1050);
DISPLAY 0.872340 (2150 -1050);
PAINT GREEN (2150 -1050);
DISPLAY INVISIBLE (2150 -1050);
FORCEPROP 2 LAST CDS_LIB logical_power
J 0
(2150 -1200);
DISPLAY INVISIBLE (2150 -1200);
FORCEPROP 1 LAST SIZE 1B
J 0
(2225 -1250);
DISPLAY 0.872340 (2225 -1250);
PAINT GREEN (2225 -1250);
DISPLAY INVISIBLE (2225 -1250);
FORCEPROP 1 LAST PATH I71
J 0
(2225 -1200);
DISPLAY 0.872340 (2225 -1200);
PAINT AQUA (2225 -1200);
DISPLAY INVISIBLE (2225 -1200);
FORCEADD Q_RES..2
(2275 -900);
FORCEPROP 1 LAST PART_NUMBER CS18452FB01
J 0
(2315 -1025);
DISPLAY 0.404255 (2315 -1025);
DISPLAY INVISIBLE (2315 -1025);
FORCEPROP 1 LAST PACK_TYPE 0402LF
J 0
(2315 -1075);
DISPLAY 0.404255 (2315 -1075);
FORCEPROP 1 LAST MATERIAL EMPTY
J 0
(2315 -975);
DISPLAY 0.404255 (2315 -975);
PAINT RED (2315 -975);
FORCEPROP 1 LAST VALUE 845
J 0
(2320 -825);
DISPLAY 0.404255 (2320 -825);
FORCEPROP 1 LAST TOLERANCE 1%
J 0
(2320 -875);
DISPLAY 0.404255 (2320 -875);
FORCEPROP 1 LAST WATTAGE 1/16W
J 0
(2315 -925);
DISPLAY 0.404255 (2315 -925);
FORCEPROP 2 LAST ROOM NIC1_P12V_MAM_MAM_BOM1
J 0
(2325 -725);
DISPLAY 1.021277 (2325 -725);
FORCEPROP 1 LAST LOCATION PR3823
J 0
(2320 -775);
DISPLAY 0.638298 (2320 -775);
FORCEPROP 1 LASTPIN (2275 -800) $PN 1
J 0
(2280 -838);
DISPLAY 0.787234 (2280 -838);
PAINT MONO (2280 -838);
FORCEPROP 1 LASTPIN (2275 -1000) $PN 2
J 0
(2280 -990);
DISPLAY 0.787234 (2280 -990);
PAINT MONO (2280 -990);
FORCEPROP 1 LAST PATH I72
J 0
(2325 -725);
DISPLAY 0.978723 (2325 -725);
PAINT WHITE (2325 -725);
DISPLAY INVISIBLE (2325 -725);
FORCEPROP 2 LAST CDS_LIB pure_quanta
J 0
(2275 -900);
DISPLAY INVISIBLE (2275 -900);
FORCEPROP 2 LAST ROOM1 NIC1_P12V_MAM_TIC_BOM2
J 0
(2325 -675);
DISPLAY 1.021277 (2325 -675);
DISPLAY INVISIBLE (2325 -675);
FORCEPROP 0 LAST $SEC 1
J 0
(2325 -725);
DISPLAY 0.680851 (2325 -725);
PAINT MONO (2325 -725);
DISPLAY INVISIBLE (2325 -725);
FORCEPROP 0 LAST CDS_SEC 1
J 0
(2325 -725);
DISPLAY 1.021277 (2325 -725);
DISPLAY INVISIBLE (2325 -725);
FORCEADD Q_CAP..1
(2250 -200);
FORCEPROP 1 LAST PART_NUMBER CH31006KB18
J 0
(2305 -308);
DISPLAY 0.404255 (2305 -308);
DISPLAY INVISIBLE (2305 -308);
FORCEPROP 1 LAST VOLTAGE 50V
J 0
(2305 -208);
DISPLAY 0.404255 (2305 -208);
FORCEPROP 1 LAST PACK_TYPE C0402
J 0
(2305 -258);
DISPLAY 0.404255 (2305 -258);
FORCEPROP 1 LAST MATERIAL EMPTY
J 0
(2300 -350);
DISPLAY 0.638298 (2300 -350);
PAINT RED (2300 -350);
FORCEPROP 1 LAST VALUE 0.01UF
J 0
(2300 -150);
DISPLAY 0.404255 (2300 -150);
FORCEPROP 1 LAST $LOCATION C2148
J 0
(2300 -100);
DISPLAY 0.510638 (2300 -100);
FORCEPROP 1 LASTPIN (2250 -100) $PN 1
J 0
(2260 -120);
DISPLAY 0.787234 (2260 -120);
PAINT MONO (2260 -120);
FORCEPROP 1 LASTPIN (2250 -300) $PN 2
J 0
(2260 -320);
DISPLAY 0.787234 (2260 -320);
PAINT MONO (2260 -320);
FORCEPROP 1 LAST TOLERANCE 10%
J 0
(2300 -250);
DISPLAY 0.638298 (2300 -250);
DISPLAY INVISIBLE (2300 -250);
FORCEPROP 2 LAST CDS_LIB pure_quanta
J 0
(2250 -200);
DISPLAY INVISIBLE (2250 -200);
FORCEPROP 1 LAST PATH I73
J 0
(2300 -50);
DISPLAY 0.978723 (2300 -50);
PAINT WHITE (2300 -50);
DISPLAY INVISIBLE (2300 -50);
FORCEPROP 0 LAST CDS_LOCATION C2148
J 0
(2300 -50);
DISPLAY 1.021277 (2300 -50);
DISPLAY INVISIBLE (2300 -50);
FORCEPROP 0 LAST $SEC 1
J 0
(2300 -50);
DISPLAY 0.680851 (2300 -50);
PAINT MONO (2300 -50);
DISPLAY INVISIBLE (2300 -50);
FORCEPROP 0 LAST CDS_SEC 1
J 0
(2300 -50);
DISPLAY 1.021277 (2300 -50);
DISPLAY INVISIBLE (2300 -50);
FORCEADD Q_RES..1
(3050 -850);
FORCEPROP 1 LAST PART_NUMBER CS00002JB13
J 0
(2875 -900);
DISPLAY 0.595745 (2875 -900);
DISPLAY INVISIBLE (2875 -900);
FORCEPROP 1 LAST TOLERANCE 5%
J 0
(3225 -850);
DISPLAY 0.595745 (3225 -850);
FORCEPROP 1 LAST VALUE 0
J 2
(3200 -850);
DISPLAY 0.595745 (3200 -850);
FORCEPROP 1 LAST PACK_TYPE 0402LF
J 0
(3200 -900);
DISPLAY 0.595745 (3200 -900);
FORCEPROP 1 LAST WATTAGE 1/16W
J 2
(2850 -900);
DISPLAY 0.595745 (2850 -900);
FORCEPROP 1 LAST MATERIAL EMPTY
J 0
(2825 -850);
DISPLAY 0.595745 (2825 -850);
PAINT RED (2825 -850);
FORCEPROP 1 LAST $LOCATION R3868
J 0
(2675 -825);
DISPLAY 0.978723 (2675 -825);
FORCEPROP 1 LASTPIN (2950 -850) $PN 1
J 0
(2962 -838);
DISPLAY 0.787234 (2962 -838);
PAINT MONO (2962 -838);
FORCEPROP 1 LASTPIN (3150 -850) $PN 2
J 0
(3112 -838);
DISPLAY 0.787234 (3112 -838);
PAINT MONO (3112 -838);
FORCEPROP 1 LAST PATH I74
J 0
(3000 -700);
DISPLAY 0.978723 (3000 -700);
PAINT WHITE (3000 -700);
DISPLAY INVISIBLE (3000 -700);
FORCEPROP 2 LAST CDS_LIB pure_quanta
J 0
(3050 -850);
DISPLAY INVISIBLE (3050 -850);
FORCEPROP 2 LAST ROOM1 NIC1_P12V_MAM_TIC_BOM2
J 0
(2675 -725);
DISPLAY 1.021277 (2675 -725);
DISPLAY INVISIBLE (2675 -725);
FORCEPROP 0 LAST CDS_LOCATION R3868
J 0
(3000 -750);
DISPLAY 1.021277 (3000 -750);
DISPLAY INVISIBLE (3000 -750);
FORCEPROP 0 LAST $SEC 1
J 0
(3000 -750);
DISPLAY 0.680851 (3000 -750);
PAINT MONO (3000 -750);
DISPLAY INVISIBLE (3000 -750);
FORCEPROP 0 LAST CDS_SEC 1
J 0
(3000 -750);
DISPLAY 1.021277 (3000 -750);
DISPLAY INVISIBLE (3000 -750);
FORCEADD Q_RES..1
(3050 -725);
FORCEPROP 1 LAST PART_NUMBER CS00002JB13
J 0
(2875 -775);
DISPLAY 0.595745 (2875 -775);
DISPLAY INVISIBLE (2875 -775);
FORCEPROP 1 LAST WATTAGE 1/16W
J 2
(2850 -775);
DISPLAY 0.595745 (2850 -775);
FORCEPROP 1 LAST PACK_TYPE 0402LF
J 0
(3200 -775);
DISPLAY 0.595745 (3200 -775);
FORCEPROP 1 LAST TOLERANCE 5%
J 0
(3225 -725);
DISPLAY 0.595745 (3225 -725);
FORCEPROP 1 LAST VALUE 0
J 2
(3200 -725);
DISPLAY 0.595745 (3200 -725);
FORCEPROP 1 LAST MATERIAL EMPTY
J 0
(2825 -725);
DISPLAY 0.595745 (2825 -725);
PAINT RED (2825 -725);
FORCEPROP 2 LAST ROOM NIC1_P12V_MAM_MAM_BOM1
J 0
(2675 -650);
DISPLAY 1.021277 (2675 -650);
FORCEPROP 1 LAST $LOCATION R3867
J 0
(2675 -700);
DISPLAY 0.978723 (2675 -700);
FORCEPROP 1 LASTPIN (2950 -725) $PN 1
J 0
(2962 -713);
DISPLAY 0.787234 (2962 -713);
PAINT MONO (2962 -713);
FORCEPROP 1 LASTPIN (3150 -725) $PN 2
J 0
(3112 -713);
DISPLAY 0.787234 (3112 -713);
PAINT MONO (3112 -713);
FORCEPROP 1 LAST PATH I75
J 0
(3000 -575);
DISPLAY 0.978723 (3000 -575);
PAINT WHITE (3000 -575);
DISPLAY INVISIBLE (3000 -575);
FORCEPROP 2 LAST CDS_LIB pure_quanta
J 0
(3050 -725);
DISPLAY INVISIBLE (3050 -725);
FORCEPROP 0 LAST CDS_LOCATION R3867
J 0
(3000 -625);
DISPLAY 1.021277 (3000 -625);
DISPLAY INVISIBLE (3000 -625);
FORCEPROP 0 LAST $SEC 1
J 0
(3000 -625);
DISPLAY 0.680851 (3000 -625);
PAINT MONO (3000 -625);
DISPLAY INVISIBLE (3000 -625);
FORCEPROP 0 LAST CDS_SEC 1
J 0
(3000 -625);
DISPLAY 1.021277 (3000 -625);
DISPLAY INVISIBLE (3000 -625);
FORCEADD Q_CAP..1
R 1
(2825 -425);
FORCEPROP 1 LAST PART_NUMBER CH23906KB14
J 0
(2875 -400);
DISPLAY 0.638298 (2875 -400);
DISPLAY INVISIBLE (2875 -400);
FORCEPROP 1 LAST VALUE 3900PF
J 0
(2725 -350);
DISPLAY 0.638298 (2725 -350);
FORCEPROP 1 LAST VOLTAGE 50V
J 0
(2925 -350);
DISPLAY 0.638298 (2925 -350);
FORCEPROP 1 LAST PACK_TYPE C0402
J 0
(2600 -475);
DISPLAY 0.638298 (2600 -475);
FORCEPROP 2 LAST ROOM NIC1_P12V_MAM_MAM_BOM1
J 0
(2925 -300);
DISPLAY 1.021277 (2925 -300);
FORCEPROP 1 LAST LOCATION PC2150
J 0
(2550 -425);
DISPLAY 0.638298 (2550 -425);
FORCEPROP 1 LASTPIN (2725 -425) $PN 1
R 1
J 0
(2745 -415);
DISPLAY 0.787234 (2745 -415);
PAINT MONO (2745 -415);
FORCEPROP 1 LASTPIN (2925 -425) $PN 2
R 1
J 0
(2945 -415);
DISPLAY 0.787234 (2945 -415);
PAINT MONO (2945 -415);
FORCEPROP 1 LAST PATH I76
R 1
J 0
(2675 -375);
DISPLAY 0.978723 (2675 -375);
PAINT WHITE (2675 -375);
DISPLAY INVISIBLE (2675 -375);
FORCEPROP 1 LAST MATERIAL EMPTY
R 1
J 0
(2825 -375);
DISPLAY 0.638298 (2825 -375);
DISPLAY INVISIBLE (2825 -375);
FORCEPROP 1 LAST TOLERANCE 10%
R 1
J 0
(2875 -375);
DISPLAY 0.638298 (2875 -375);
DISPLAY INVISIBLE (2875 -375);
FORCEPROP 2 LAST CDS_LIB pure_quanta
R 1
J 0
(2825 -425);
DISPLAY INVISIBLE (2825 -425);
FORCEPROP 2 LAST ROOM1 NIC1_P12V_MAM_TIC_BOM2
J 0
(2925 -250);
DISPLAY 1.021277 (2925 -250);
DISPLAY INVISIBLE (2925 -250);
FORCEPROP 0 LAST $SEC 1
R 1
J 0
(2925 -300);
DISPLAY 0.680851 (2925 -300);
PAINT MONO (2925 -300);
DISPLAY INVISIBLE (2925 -300);
FORCEPROP 0 LAST CDS_SEC 1
R 1
J 0
(2925 -300);
DISPLAY 1.021277 (2925 -300);
DISPLAY INVISIBLE (2925 -300);
FORCEADD Q_RES..2
(2550 -200);
FORCEPROP 1 LAST PART_NUMBER CS61002FB02
J 0
(2575 -300);
DISPLAY 0.404255 (2575 -300);
DISPLAY INVISIBLE (2575 -300);
FORCEPROP 1 LAST VALUE 10M
J 0
(2580 -100);
DISPLAY 0.404255 (2580 -100);
FORCEPROP 1 LAST WATTAGE 1/16W
J 0
(2575 -200);
DISPLAY 0.404255 (2575 -200);
FORCEPROP 1 LAST PACK_TYPE 0402LF
J 0
(2575 -350);
DISPLAY 0.404255 (2575 -350);
FORCEPROP 1 LAST MATERIAL EMPTY
J 0
(2575 -250);
DISPLAY 0.404255 (2575 -250);
PAINT RED (2575 -250);
FORCEPROP 1 LAST TOLERANCE 1%
J 0
(2580 -150);
DISPLAY 0.404255 (2580 -150);
FORCEPROP 2 LAST ROOM NIC1_P12V_MAM_MAM_BOM1
J 0
(2525 50);
DISPLAY 1.021277 (2525 50);
FORCEPROP 1 LAST LOCATION PR4522
J 0
(2580 -50);
DISPLAY 0.787234 (2580 -50);
FORCEPROP 1 LASTPIN (2550 -100) $PN 1
J 0
(2555 -138);
DISPLAY 0.787234 (2555 -138);
PAINT MONO (2555 -138);
FORCEPROP 1 LASTPIN (2550 -300) $PN 2
J 0
(2555 -290);
DISPLAY 0.787234 (2555 -290);
PAINT MONO (2555 -290);
FORCEPROP 1 LAST PATH I77
J 0
(2600 -25);
DISPLAY 0.978723 (2600 -25);
PAINT WHITE (2600 -25);
DISPLAY INVISIBLE (2600 -25);
FORCEPROP 2 LAST CDS_LIB pure_quanta
J 0
(2550 -200);
DISPLAY INVISIBLE (2550 -200);
FORCEPROP 2 LAST ROOM1 NIC1_P12V_MAM_TIC_BOM2
J 0
(2600 50);
DISPLAY 1.021277 (2600 50);
DISPLAY INVISIBLE (2600 50);
FORCEPROP 0 LAST $SEC 1
J 0
(2600 0);
DISPLAY 0.680851 (2600 0);
PAINT MONO (2600 0);
DISPLAY INVISIBLE (2600 0);
FORCEPROP 0 LAST CDS_SEC 1
J 0
(2600 0);
DISPLAY 1.021277 (2600 0);
DISPLAY INVISIBLE (2600 0);
FORCEADD Q_RES..1
(2900 -525);
FORCEPROP 1 LAST PART_NUMBER CS00002JB13
J 0
(2725 -575);
DISPLAY 0.595745 (2725 -575);
DISPLAY INVISIBLE (2725 -575);
FORCEPROP 1 LAST PACK_TYPE 0402LF
J 0
(3050 -575);
DISPLAY 0.595745 (3050 -575);
FORCEPROP 1 LAST TOLERANCE 5%
J 0
(3075 -525);
DISPLAY 0.595745 (3075 -525);
FORCEPROP 1 LAST VALUE 0
J 2
(3050 -525);
DISPLAY 0.595745 (3050 -525);
FORCEPROP 1 LAST MATERIAL EMPTY
J 0
(2675 -525);
DISPLAY 0.595745 (2675 -525);
PAINT RED (2675 -525);
FORCEPROP 1 LAST WATTAGE 1/16W
J 2
(2700 -575);
DISPLAY 0.595745 (2700 -575);
FORCEPROP 2 LAST ROOM NIC1_P12V_MAM_MAM_BOM1
J 0
(3075 -475);
DISPLAY 1.021277 (3075 -475);
FORCEPROP 1 LAST $LOCATION R3831
J 0
(2550 -525);
DISPLAY 0.638298 (2550 -525);
FORCEPROP 1 LASTPIN (2800 -525) $PN 1
J 0
(2812 -513);
DISPLAY 0.787234 (2812 -513);
PAINT MONO (2812 -513);
FORCEPROP 1 LASTPIN (3000 -525) $PN 2
J 0
(2962 -513);
DISPLAY 0.787234 (2962 -513);
PAINT MONO (2962 -513);
FORCEPROP 1 LAST PATH I78
J 0
(2850 -375);
DISPLAY 0.978723 (2850 -375);
PAINT WHITE (2850 -375);
DISPLAY INVISIBLE (2850 -375);
FORCEPROP 2 LAST CDS_LIB pure_quanta
J 0
(2900 -525);
DISPLAY INVISIBLE (2900 -525);
FORCEPROP 2 LAST ROOM1 NIC1_P12V_MAM_TIC_BOM2
J 0
(3075 -425);
DISPLAY 1.021277 (3075 -425);
DISPLAY INVISIBLE (3075 -425);
FORCEPROP 0 LAST CDS_LOCATION R3831
J 0
(2850 -450);
DISPLAY 1.021277 (2850 -450);
DISPLAY INVISIBLE (2850 -450);
FORCEPROP 0 LAST $SEC 1
J 0
(2850 -450);
DISPLAY 0.680851 (2850 -450);
PAINT MONO (2850 -450);
DISPLAY INVISIBLE (2850 -450);
FORCEPROP 0 LAST CDS_SEC 1
J 0
(2850 -450);
DISPLAY 1.021277 (2850 -450);
DISPLAY INVISIBLE (2850 -450);
FORCEADD GND..1
(3000 -500);
FORCEPROP 3 LASTPIN (3000 -450) SIG_NAME GND\g
J 0
(3010 -440);
DISPLAY 0.659574 (3010 -440);
PAINT MONO (3010 -440);
DISPLAY INVISIBLE (3010 -440);
FORCEPROP 1 LAST HDL_POWER GND
J 0
(3000 -350);
DISPLAY 0.872340 (3000 -350);
PAINT GREEN (3000 -350);
DISPLAY INVISIBLE (3000 -350);
FORCEPROP 2 LAST CDS_LIB logical_power
J 0
(3000 -500);
DISPLAY INVISIBLE (3000 -500);
FORCEPROP 1 LAST SIZE 1B
J 0
(3075 -550);
DISPLAY 0.872340 (3075 -550);
PAINT GREEN (3075 -550);
DISPLAY INVISIBLE (3075 -550);
FORCEPROP 1 LAST PATH I79
J 0
(3075 -500);
DISPLAY 0.872340 (3075 -500);
PAINT AQUA (3075 -500);
DISPLAY INVISIBLE (3075 -500);
FORCEADD OFFPAGE..1
(-2725 -1800);
FORCEPROP 2 LAST $XR1 165 
J 0
(-3127 -1800);
DISPLAY 0.638298 (-3127 -1800);
PAINT MONO (-3127 -1800);
FORCEPROP 2 LAST $XR0 159 
J 0
(-3007 -1800);
DISPLAY 0.638298 (-3007 -1800);
PAINT MONO (-3007 -1800);
FORCEPROP 1 LAST COMMENT_BODY TRUE
J 0
(-2600 -1900);
DISPLAY 0.872340 (-2600 -1900);
PAINT GREEN (-2600 -1900);
DISPLAY INVISIBLE (-2600 -1900);
FORCEPROP 1 LAST OFFPAGE TRUE
J 0
(-2400 -1925);
DISPLAY 0.872340 (-2400 -1925);
PAINT GREEN (-2400 -1925);
DISPLAY INVISIBLE (-2400 -1925);
FORCEPROP 2 LAST CDS_LIB standard
J 0
(-2725 -1800);
PAINT MONO (-2725 -1800);
DISPLAY INVISIBLE (-2725 -1800);
FORCEPROP 2 LAST PATH I8
J 0
(-3000 -1750);
DISPLAY 1.021277 (-3000 -1750);
DISPLAY INVISIBLE (-3000 -1750);
FORCEADD Q_RES..2
(3250 -275);
FORCEPROP 1 LAST PART_NUMBER CS41002FB09
J 0
(3290 -400);
DISPLAY 0.510638 (3290 -400);
DISPLAY INVISIBLE (3290 -400);
FORCEPROP 1 LAST MATERIAL EMPTY
J 0
(3290 -350);
DISPLAY 0.510638 (3290 -350);
PAINT RED (3290 -350);
FORCEPROP 1 LAST VALUE 100K
J 0
(3295 -200);
DISPLAY 0.510638 (3295 -200);
FORCEPROP 1 LAST TOLERANCE 1%
J 0
(3295 -250);
DISPLAY 0.510638 (3295 -250);
FORCEPROP 1 LAST WATTAGE 1/16W
J 0
(3290 -300);
DISPLAY 0.510638 (3290 -300);
FORCEPROP 1 LAST PACK_TYPE 0402LF
J 0
(3290 -450);
DISPLAY 0.510638 (3290 -450);
FORCEPROP 2 LAST ROOM NIC1_P12V_MAM_MAM_BOM1
J 0
(3300 -100);
DISPLAY 1.021277 (3300 -100);
FORCEPROP 1 LAST LOCATION R3816
J 0
(3295 -150);
DISPLAY 0.638298 (3295 -150);
FORCEPROP 1 LASTPIN (3250 -175) $PN 1
J 0
(3255 -213);
DISPLAY 0.787234 (3255 -213);
PAINT MONO (3255 -213);
FORCEPROP 1 LASTPIN (3250 -375) $PN 2
J 0
(3255 -365);
DISPLAY 0.787234 (3255 -365);
PAINT MONO (3255 -365);
FORCEPROP 1 LAST PATH I80
J 0
(3300 -100);
DISPLAY 0.978723 (3300 -100);
PAINT WHITE (3300 -100);
DISPLAY INVISIBLE (3300 -100);
FORCEPROP 2 LAST CDS_LIB pure_quanta
J 0
(3250 -275);
DISPLAY INVISIBLE (3250 -275);
FORCEPROP 2 LAST ROOM1 NIC1_P12V_MAM_TIC_BOM2
J 0
(3300 -50);
DISPLAY 1.021277 (3300 -50);
DISPLAY INVISIBLE (3300 -50);
FORCEPROP 0 LAST $SEC 1
J 0
(3300 -100);
DISPLAY 0.680851 (3300 -100);
PAINT MONO (3300 -100);
DISPLAY INVISIBLE (3300 -100);
FORCEPROP 0 LAST CDS_SEC 1
J 0
(3300 -100);
DISPLAY 1.021277 (3300 -100);
DISPLAY INVISIBLE (3300 -100);
FORCEADD Q_RES..2
(3675 -275);
FORCEPROP 1 LAST PART_NUMBER CS41002FB09
J 0
(3715 -400);
DISPLAY 0.510638 (3715 -400);
DISPLAY INVISIBLE (3715 -400);
FORCEPROP 1 LAST TOLERANCE 1%
J 0
(3720 -250);
DISPLAY 0.510638 (3720 -250);
FORCEPROP 1 LAST VALUE 100K
J 0
(3720 -200);
DISPLAY 0.510638 (3720 -200);
FORCEPROP 1 LAST WATTAGE 1/16W
J 0
(3715 -300);
DISPLAY 0.510638 (3715 -300);
FORCEPROP 1 LAST PACK_TYPE 0402LF
J 0
(3715 -450);
DISPLAY 0.510638 (3715 -450);
FORCEPROP 1 LAST MATERIAL EMPTY
J 0
(3715 -350);
DISPLAY 0.510638 (3715 -350);
PAINT RED (3715 -350);
FORCEPROP 2 LAST ROOM NIC1_P12V_MAM_MAM_BOM1
J 0
(3625 25);
DISPLAY 1.021277 (3625 25);
FORCEPROP 1 LAST LOCATION R3825
J 0
(3720 -150);
DISPLAY 0.638298 (3720 -150);
FORCEPROP 1 LASTPIN (3675 -175) $PN 1
J 0
(3680 -213);
DISPLAY 0.787234 (3680 -213);
PAINT MONO (3680 -213);
FORCEPROP 1 LASTPIN (3675 -375) $PN 2
J 0
(3680 -365);
DISPLAY 0.787234 (3680 -365);
PAINT MONO (3680 -365);
FORCEPROP 1 LAST PATH I81
J 0
(3725 -100);
DISPLAY 0.978723 (3725 -100);
PAINT WHITE (3725 -100);
DISPLAY INVISIBLE (3725 -100);
FORCEPROP 2 LAST CDS_LIB pure_quanta
J 0
(3675 -275);
DISPLAY INVISIBLE (3675 -275);
FORCEPROP 2 LAST ROOM1 NIC1_P12V_MAM_TIC_BOM2
J 0
(3725 -50);
DISPLAY 1.021277 (3725 -50);
DISPLAY INVISIBLE (3725 -50);
FORCEPROP 0 LAST $SEC 1
J 0
(3725 -100);
DISPLAY 0.680851 (3725 -100);
PAINT MONO (3725 -100);
DISPLAY INVISIBLE (3725 -100);
FORCEPROP 0 LAST CDS_SEC 1
J 0
(3725 -100);
DISPLAY 1.021277 (3725 -100);
DISPLAY INVISIBLE (3725 -100);
FORCEADD OFFPAGE..2
(4300 -850);
PAINT AQUA (4300 -850);
FORCEPROP 2 LAST $XR0 250 
J 0
(4489 -850);
DISPLAY 0.638298 (4489 -850);
PAINT MONO (4489 -850);
FORCEPROP 1 LAST COMMENT_BODY TRUE
J 0
(4255 -945);
DISPLAY 0.872340 (4255 -945);
PAINT GREEN (4255 -945);
DISPLAY INVISIBLE (4255 -945);
FORCEPROP 1 LAST OFFPAGE TRUE
J 0
(4625 -975);
DISPLAY 0.872340 (4625 -975);
PAINT AQUA (4625 -975);
DISPLAY INVISIBLE (4625 -975);
FORCEPROP 2 LAST CDS_LIB standard
J 0
(4300 -850);
DISPLAY INVISIBLE (4300 -850);
FORCEPROP 2 LAST PATH I82
J 0
(4500 -800);
DISPLAY 1.021277 (4500 -800);
DISPLAY INVISIBLE (4500 -800);
FORCEADD OFFPAGE..2
(4300 -725);
PAINT AQUA (4300 -725);
FORCEPROP 2 LAST $XR0 250 
J 0
(4489 -725);
DISPLAY 0.638298 (4489 -725);
PAINT MONO (4489 -725);
FORCEPROP 1 LAST COMMENT_BODY TRUE
J 0
(4255 -820);
DISPLAY 0.872340 (4255 -820);
PAINT GREEN (4255 -820);
DISPLAY INVISIBLE (4255 -820);
FORCEPROP 1 LAST OFFPAGE TRUE
J 0
(4625 -850);
DISPLAY 0.872340 (4625 -850);
PAINT AQUA (4625 -850);
DISPLAY INVISIBLE (4625 -850);
FORCEPROP 2 LAST CDS_LIB standard
J 0
(4300 -725);
DISPLAY INVISIBLE (4300 -725);
FORCEPROP 2 LAST PATH I83
J 0
(4500 -675);
DISPLAY 1.021277 (4500 -675);
DISPLAY INVISIBLE (4500 -675);
FORCEADD OFFPAGE..2
(4150 -525);
PAINT AQUA (4150 -525);
FORCEPROP 2 LAST $XR2 214 
J 0
(4339 -561);
DISPLAY 0.638298 (4339 -561);
PAINT MONO (4339 -561);
FORCEPROP 2 LAST $XR1 164 
J 0
(4459 -525);
DISPLAY 0.638298 (4459 -525);
PAINT MONO (4459 -525);
FORCEPROP 2 LAST $XR0 163 
J 0
(4339 -525);
DISPLAY 0.638298 (4339 -525);
PAINT MONO (4339 -525);
FORCEPROP 1 LAST OFFPAGE TRUE
J 0
(4475 -650);
DISPLAY 0.872340 (4475 -650);
PAINT AQUA (4475 -650);
DISPLAY INVISIBLE (4475 -650);
FORCEPROP 1 LAST COMMENT_BODY TRUE
J 0
(4105 -620);
DISPLAY 0.872340 (4105 -620);
PAINT GREEN (4105 -620);
DISPLAY INVISIBLE (4105 -620);
FORCEPROP 2 LAST CDS_LIB standard
J 0
(4150 -525);
DISPLAY INVISIBLE (4150 -525);
FORCEPROP 2 LAST PATH I84
J 0
(4475 -475);
DISPLAY 1.021277 (4475 -475);
DISPLAY INVISIBLE (4475 -475);
FORCEADD Q_RES..2
(150 200);
FORCEPROP 1 LAST PART_NUMBER CS01002FB07
J 0
(200 150);
DISPLAY 0.404255 (200 150);
DISPLAY INVISIBLE (200 150);
FORCEPROP 1 LAST WATTAGE 1/16W
J 0
(200 200);
DISPLAY 0.404255 (200 200);
FORCEPROP 1 LAST PACK_TYPE 0402LF
J 0
(200 125);
DISPLAY 0.404255 (200 125);
FORCEPROP 1 LAST TOLERANCE 1%
J 0
(200 225);
DISPLAY 0.404255 (200 225);
FORCEPROP 1 LAST MATERIAL EMPTY
J 0
(200 175);
DISPLAY 0.404255 (200 175);
PAINT RED (200 175);
FORCEPROP 1 LAST VALUE 10
J 0
(200 250);
DISPLAY 0.404255 (200 250);
FORCEPROP 1 LAST LOCATION PR3830
J 0
(200 275);
DISPLAY 0.638298 (200 275);
FORCEPROP 1 LASTPIN (150 300) $PN 1
J 0
(155 262);
DISPLAY 0.787234 (155 262);
PAINT MONO (155 262);
FORCEPROP 1 LASTPIN (150 100) $PN 2
J 0
(155 110);
DISPLAY 0.787234 (155 110);
PAINT MONO (155 110);
FORCEPROP 1 LAST PATH I85
J 0
(200 375);
DISPLAY 0.978723 (200 375);
PAINT WHITE (200 375);
DISPLAY INVISIBLE (200 375);
FORCEPROP 2 LAST CDS_LIB pure_quanta
J 0
(150 200);
DISPLAY INVISIBLE (150 200);
FORCEPROP 2 LAST ROOM1 NIC1_P12V_MAM_TIC_BOM2
J 0
(200 375);
DISPLAY 1.021277 (200 375);
DISPLAY INVISIBLE (200 375);
FORCEPROP 2 LAST ROOM NIC1_P12V_MAM_MAM_BOM1
J 0
(200 325);
DISPLAY 1.021277 (200 325);
DISPLAY INVISIBLE (200 325);
FORCEPROP 0 LAST $SEC 1
J 0
(200 325);
DISPLAY 0.680851 (200 325);
PAINT MONO (200 325);
DISPLAY INVISIBLE (200 325);
FORCEPROP 0 LAST CDS_SEC 1
J 0
(200 325);
DISPLAY 1.021277 (200 325);
DISPLAY INVISIBLE (200 325);
FORCEADD GND..1
(275 1725);
FORCEPROP 3 LASTPIN (275 1775) SIG_NAME GND\g
J 0
(285 1785);
DISPLAY 0.659574 (285 1785);
PAINT MONO (285 1785);
DISPLAY INVISIBLE (285 1785);
FORCEPROP 1 LAST HDL_POWER GND
J 0
(275 1875);
DISPLAY 0.872340 (275 1875);
PAINT GREEN (275 1875);
DISPLAY INVISIBLE (275 1875);
FORCEPROP 2 LAST CDS_LIB logical_power
J 0
(275 1725);
DISPLAY INVISIBLE (275 1725);
FORCEPROP 1 LAST SIZE 1B
J 0
(350 1675);
DISPLAY 0.872340 (350 1675);
PAINT GREEN (350 1675);
DISPLAY INVISIBLE (350 1675);
FORCEPROP 1 LAST PATH I86
J 0
(350 1725);
DISPLAY 0.872340 (350 1725);
PAINT AQUA (350 1725);
DISPLAY INVISIBLE (350 1725);
FORCEADD Q_CAP..1
R 1
(500 1800);
FORCEPROP 1 LAST PART_NUMBER CH5104KEB02
J 0
(550 1750);
DISPLAY 0.510638 (550 1750);
DISPLAY INVISIBLE (550 1750);
FORCEPROP 1 LAST PACK_TYPE C0402
J 0
(325 1750);
DISPLAY 0.510638 (325 1750);
FORCEPROP 1 LAST VALUE 1UF
J 0
(475 1850);
DISPLAY 0.510638 (475 1850);
FORCEPROP 1 LAST VOLTAGE 25V
J 0
(625 1850);
DISPLAY 0.510638 (625 1850);
FORCEPROP 2 LAST ROOM NIC1_P3V3_BOM1
J 0
(325 1900);
DISPLAY 0.319149 (325 1900);
FORCEPROP 1 LAST LOCATION PC2147
J 0
(325 1850);
DISPLAY 0.638298 (325 1850);
FORCEPROP 1 LASTPIN (400 1800) $PN 1
R 1
J 0
(420 1810);
DISPLAY 0.787234 (420 1810);
PAINT MONO (420 1810);
FORCEPROP 1 LASTPIN (600 1800) $PN 2
R 1
J 0
(620 1810);
DISPLAY 0.787234 (620 1810);
PAINT MONO (620 1810);
FORCEPROP 1 LAST PATH I87
R 1
J 0
(350 1850);
DISPLAY 0.978723 (350 1850);
PAINT WHITE (350 1850);
DISPLAY INVISIBLE (350 1850);
FORCEPROP 1 LAST TOLERANCE 10%
R 1
J 0
(550 1850);
DISPLAY 0.638298 (550 1850);
DISPLAY INVISIBLE (550 1850);
FORCEPROP 2 LAST CDS_LIB pure_quanta
J 0
(500 1800);
DISPLAY INVISIBLE (500 1800);
FORCEPROP 1 LAST MATERIAL X6S
R 1
J 0
(500 1850);
DISPLAY 0.638298 (500 1850);
DISPLAY INVISIBLE (500 1850);
FORCEPROP 0 LAST $SEC 1
R 1
J 0
(325 1900);
DISPLAY 0.680851 (325 1900);
PAINT MONO (325 1900);
DISPLAY INVISIBLE (325 1900);
FORCEPROP 0 LAST CDS_SEC 1
R 1
J 0
(325 1900);
DISPLAY 1.021277 (325 1900);
DISPLAY INVISIBLE (325 1900);
FORCEADD GND..1
(800 1000);
FORCEPROP 3 LASTPIN (800 1050) SIG_NAME GND\g
J 0
(810 1060);
DISPLAY 0.659574 (810 1060);
PAINT MONO (810 1060);
DISPLAY INVISIBLE (810 1060);
FORCEPROP 1 LAST HDL_POWER GND
J 0
(800 1150);
DISPLAY 0.872340 (800 1150);
PAINT GREEN (800 1150);
DISPLAY INVISIBLE (800 1150);
FORCEPROP 2 LAST CDS_LIB logical_power
J 0
(800 1000);
DISPLAY INVISIBLE (800 1000);
FORCEPROP 1 LAST SIZE 1B
J 0
(875 950);
DISPLAY 0.872340 (875 950);
PAINT GREEN (875 950);
DISPLAY INVISIBLE (875 950);
FORCEPROP 1 LAST PATH I88
J 0
(875 1000);
DISPLAY 0.872340 (875 1000);
PAINT AQUA (875 1000);
DISPLAY INVISIBLE (875 1000);
FORCEADD Q_RES..2
(800 1300);
FORCEPROP 1 LAST PART_NUMBER CS25362FB02
J 0
(850 1225);
DISPLAY 0.510638 (850 1225);
DISPLAY INVISIBLE (850 1225);
FORCEPROP 1 LAST TOLERANCE 1%
J 0
(850 1300);
DISPLAY 0.510638 (850 1300);
FORCEPROP 1 LAST VALUE 5.36K
J 0
(850 1325);
DISPLAY 0.510638 (850 1325);
FORCEPROP 1 LAST MATERIAL CHIP
J 0
(850 1250);
DISPLAY 0.510638 (850 1250);
FORCEPROP 1 LAST WATTAGE 1/16W
J 0
(850 1275);
DISPLAY 0.510638 (850 1275);
FORCEPROP 1 LAST PACK_TYPE 0402LF
J 0
(850 1200);
DISPLAY 0.510638 (850 1200);
FORCEPROP 2 LAST ROOM NIC1_P3V3_BOM1
J 0
(850 1400);
DISPLAY 0.404255 (850 1400);
FORCEPROP 1 LAST LOCATION PR3822
J 0
(850 1350);
DISPLAY 0.638298 (850 1350);
FORCEPROP 1 LASTPIN (800 1400) $PN 1
J 0
(805 1362);
DISPLAY 0.787234 (805 1362);
PAINT MONO (805 1362);
FORCEPROP 1 LASTPIN (800 1200) $PN 2
J 0
(805 1210);
DISPLAY 0.787234 (805 1210);
PAINT MONO (805 1210);
FORCEPROP 1 LAST PATH I89
J 0
(850 1475);
DISPLAY 0.978723 (850 1475);
PAINT WHITE (850 1475);
DISPLAY INVISIBLE (850 1475);
FORCEPROP 2 LAST CDS_LIB pure_quanta
J 0
(800 1300);
DISPLAY INVISIBLE (800 1300);
FORCEPROP 0 LAST $SEC 1
J 0
(850 1450);
DISPLAY 0.680851 (850 1450);
PAINT MONO (850 1450);
DISPLAY INVISIBLE (850 1450);
FORCEPROP 0 LAST CDS_SEC 1
J 0
(850 1425);
DISPLAY INVISIBLE (850 1425);
FORCEADD OFFPAGE..1
(-2725 -1700);
FORCEPROP 2 LAST $XR1 165 
J 0
(-3127 -1700);
DISPLAY 0.638298 (-3127 -1700);
PAINT MONO (-3127 -1700);
FORCEPROP 2 LAST $XR0 159 
J 0
(-3007 -1700);
DISPLAY 0.638298 (-3007 -1700);
PAINT MONO (-3007 -1700);
FORCEPROP 1 LAST COMMENT_BODY TRUE
J 0
(-2600 -1800);
DISPLAY 0.872340 (-2600 -1800);
PAINT GREEN (-2600 -1800);
DISPLAY INVISIBLE (-2600 -1800);
FORCEPROP 1 LAST OFFPAGE TRUE
J 0
(-2400 -1825);
DISPLAY 0.872340 (-2400 -1825);
PAINT GREEN (-2400 -1825);
DISPLAY INVISIBLE (-2400 -1825);
FORCEPROP 2 LAST CDS_LIB standard
J 0
(-2725 -1700);
PAINT MONO (-2725 -1700);
DISPLAY INVISIBLE (-2725 -1700);
FORCEPROP 2 LAST PATH I9
J 0
(-3000 -1650);
DISPLAY 1.021277 (-3000 -1650);
DISPLAY INVISIBLE (-3000 -1650);
FORCEADD MAX15090BEWIT..1
(1550 1800);
FORCEPROP 1 LAST PART_NUMBER AL015080B00
J 0
(1297 2444);
DISPLAY 0.723404 (1297 2444);
PAINT GREEN (1297 2444);
DISPLAY INVISIBLE (1297 2444);
FORCEPROP 1 LAST MATERIAL IC
J 0
(1297 2355);
DISPLAY 0.723404 (1297 2355);
PAINT GREEN (1297 2355);
FORCEPROP 2 LAST VALUE MAX15090BEWI+T
J 0
(1300 2575);
DISPLAY 1.021277 (1300 2575);
FORCEPROP 2 LAST PART_TYPE SMLF
J 0
(1300 2625);
DISPLAY 1.021277 (1300 2625);
FORCEPROP 2 LAST ROOM NIC1_P3V3_BOM1
J 0
(1300 2675);
DISPLAY 1.021277 (1300 2675);
FORCEPROP 1 LAST LOCATION PU200
J 0
(1297 2528);
DISPLAY 0.723404 (1297 2528);
PAINT GREEN (1297 2528);
FORCEPROP 0 LASTPIN (1150 1500) $PN B1
J 2
(1140 1510);
DISPLAY 0.680851 (1140 1510);
PAINT MONO (1140 1510);
FORCEPROP 0 LASTPIN (1950 1500) $PN A7
J 0
(1960 1510);
DISPLAY 0.680851 (1960 1510);
PAINT MONO (1960 1510);
FORCEPROP 0 LASTPIN (1150 1400) $PN B7
J 2
(1140 1410);
DISPLAY 0.680851 (1140 1410);
PAINT MONO (1140 1410);
FORCEPROP 0 LASTPIN (1950 1700) $PN C7
J 0
(1960 1710);
DISPLAY 0.680851 (1960 1710);
PAINT MONO (1960 1710);
FORCEPROP 0 LASTPIN (1950 1900) $PN A6
J 0
(1960 1910);
DISPLAY 0.680851 (1960 1910);
PAINT MONO (1960 1910);
FORCEPROP 0 LASTPIN (1950 1400) $PN B2
J 0
(1960 1410);
DISPLAY 0.680851 (1960 1410);
PAINT MONO (1960 1410);
FORCEPROP 0 LASTPIN (1950 1350) $PN C1
J 0
(1960 1360);
DISPLAY 0.680851 (1960 1360);
PAINT MONO (1960 1360);
FORCEPROP 0 LASTPIN (1950 1300) $PN C2
J 0
(1960 1310);
DISPLAY 0.680851 (1960 1310);
PAINT MONO (1960 1310);
FORCEPROP 0 LASTPIN (1150 2300) $PN A3
J 2
(1140 2310);
DISPLAY 0.680851 (1140 2310);
PAINT MONO (1140 2310);
FORCEPROP 0 LASTPIN (1150 2250) $PN A5
J 2
(1140 2260);
DISPLAY 0.680851 (1140 2260);
PAINT MONO (1140 2260);
FORCEPROP 0 LASTPIN (1150 2200) $PN B3
J 2
(1140 2210);
DISPLAY 0.680851 (1140 2210);
PAINT MONO (1140 2210);
FORCEPROP 0 LASTPIN (1150 2150) $PN B5
J 2
(1140 2160);
DISPLAY 0.680851 (1140 2160);
PAINT MONO (1140 2160);
FORCEPROP 0 LASTPIN (1150 2100) $PN C3
J 2
(1140 2110);
DISPLAY 0.680851 (1140 2110);
PAINT MONO (1140 2110);
FORCEPROP 0 LASTPIN (1150 2050) $PN C5
J 2
(1140 2060);
DISPLAY 0.680851 (1140 2060);
PAINT MONO (1140 2060);
FORCEPROP 0 LASTPIN (1150 2000) $PN D5
J 2
(1140 2010);
DISPLAY 0.680851 (1140 2010);
PAINT MONO (1140 2010);
FORCEPROP 0 LASTPIN (1950 1600) $PN A1
J 0
(1960 1610);
DISPLAY 0.680851 (1960 1610);
PAINT MONO (1960 1610);
FORCEPROP 0 LASTPIN (1950 2300) $PN A4
J 0
(1960 2310);
DISPLAY 0.680851 (1960 2310);
PAINT MONO (1960 2310);
FORCEPROP 0 LASTPIN (1950 2250) $PN B4
J 0
(1960 2260);
DISPLAY 0.680851 (1960 2260);
PAINT MONO (1960 2260);
FORCEPROP 0 LASTPIN (1950 2200) $PN B6
J 0
(1960 2210);
DISPLAY 0.680851 (1960 2210);
PAINT MONO (1960 2210);
FORCEPROP 0 LASTPIN (1950 2150) $PN C4
J 0
(1960 2160);
DISPLAY 0.680851 (1960 2160);
PAINT MONO (1960 2160);
FORCEPROP 0 LASTPIN (1950 2100) $PN C6
J 0
(1960 2110);
DISPLAY 0.680851 (1960 2110);
PAINT MONO (1960 2110);
FORCEPROP 0 LASTPIN (1950 2050) $PN D4
J 0
(1960 2060);
DISPLAY 0.680851 (1960 2060);
PAINT MONO (1960 2060);
FORCEPROP 0 LASTPIN (1950 2000) $PN D6
J 0
(1960 2010);
DISPLAY 0.680851 (1960 2010);
PAINT MONO (1960 2010);
FORCEPROP 0 LASTPIN (1150 1600) $PN D3
J 2
(1140 1610);
DISPLAY 0.680851 (1140 1610);
PAINT MONO (1140 1610);
FORCEPROP 0 LASTPIN (1950 1800) $PN D7
J 0
(1960 1810);
DISPLAY 0.680851 (1960 1810);
PAINT MONO (1960 1810);
FORCEPROP 0 LASTPIN (1150 1800) $PN D1
J 2
(1140 1810);
DISPLAY 0.680851 (1140 1810);
PAINT MONO (1140 1810);
FORCEPROP 0 LASTPIN (1150 1700) $PN D2
J 2
(1140 1710);
DISPLAY 0.680851 (1140 1710);
PAINT MONO (1140 1710);
FORCEPROP 0 LASTPIN (1150 1900) $PN A2
J 2
(1140 1910);
DISPLAY 0.680851 (1140 1910);
PAINT MONO (1140 1910);
FORCEPROP 1 LAST PATH I90
J 0
(1800 1250);
DISPLAY 0.723404 (1800 1250);
PAINT GREEN (1800 1250);
DISPLAY INVISIBLE (1800 1250);
FORCEPROP 2 LAST CDS_LIB pure_quanta
J 0
(1550 1800);
DISPLAY INVISIBLE (1550 1800);
FORCEPROP 1 LAST PIN_NAMES_ROTATE True
J 0
(1550 1800);
DISPLAY 0.489362 (1550 1800);
PAINT GREEN (1550 1800);
DISPLAY INVISIBLE (1550 1800);
FORCEPROP 1 LAST CDS_LMAN_SYM_OUTLINE -250,550,250,-550
J 0
(1550 1800);
DISPLAY 0.468085 (1550 1800);
PAINT GREEN (1550 1800);
DISPLAY INVISIBLE (1550 1800);
FORCEPROP 0 LAST $SEC 1
J 0
(1300 2675);
DISPLAY 0.680851 (1300 2675);
PAINT MONO (1300 2675);
DISPLAY INVISIBLE (1300 2675);
FORCEPROP 0 LAST CDS_SEC 1
J 0
(1300 2675);
DISPLAY 1.021277 (1300 2675);
DISPLAY INVISIBLE (1300 2675);
FORCEADD Q_CAP..1
(275 2100);
FORCEPROP 1 LAST PART_NUMBER CH5104KEB02
J 0
(325 2000);
DISPLAY 0.510638 (325 2000);
DISPLAY INVISIBLE (325 2000);
FORCEPROP 1 LAST PACK_TYPE C0402
J 0
(325 2025);
DISPLAY 0.510638 (325 2025);
FORCEPROP 1 LAST VOLTAGE 25V
J 0
(325 2050);
DISPLAY 0.510638 (325 2050);
FORCEPROP 1 LAST MATERIAL X6S
J 0
(325 2075);
DISPLAY 0.510638 (325 2075);
FORCEPROP 1 LAST VALUE 1UF
J 0
(325 2100);
DISPLAY 0.510638 (325 2100);
FORCEPROP 2 LAST ROOM NIC1_P3V3_BOM1
J 0
(325 2175);
DISPLAY 0.319149 (325 2175);
FORCEPROP 1 LAST $LOCATION PC190
J 0
(325 2125);
DISPLAY 0.638298 (325 2125);
FORCEPROP 1 LASTPIN (275 2200) $PN 1
J 0
(285 2180);
DISPLAY 0.787234 (285 2180);
PAINT MONO (285 2180);
FORCEPROP 1 LASTPIN (275 2000) $PN 2
J 0
(285 1980);
DISPLAY 0.787234 (285 1980);
PAINT MONO (285 1980);
FORCEPROP 1 LAST PATH I91
J 0
(325 2250);
DISPLAY 0.978723 (325 2250);
PAINT WHITE (325 2250);
DISPLAY INVISIBLE (325 2250);
FORCEPROP 1 LAST TOLERANCE 10%
J 0
(325 2050);
DISPLAY 0.638298 (325 2050);
DISPLAY INVISIBLE (325 2050);
FORCEPROP 2 LAST CDS_LIB pure_quanta
J 0
(275 2100);
DISPLAY INVISIBLE (275 2100);
FORCEPROP 0 LAST CDS_LOCATION PC190
J 0
(325 2175);
DISPLAY 1.021277 (325 2175);
DISPLAY INVISIBLE (325 2175);
FORCEPROP 0 LAST $SEC 1
J 0
(325 2175);
DISPLAY 0.680851 (325 2175);
PAINT MONO (325 2175);
DISPLAY INVISIBLE (325 2175);
FORCEPROP 0 LAST CDS_SEC 1
J 0
(325 2175);
DISPLAY 1.021277 (325 2175);
DISPLAY INVISIBLE (325 2175);
FORCEADD Q_RES..2
(275 2525);
FORCEPROP 1 LAST PART_NUMBER CS01002FB07
J 0
(325 2475);
DISPLAY 0.404255 (325 2475);
DISPLAY INVISIBLE (325 2475);
FORCEPROP 1 LAST WATTAGE 1/16W
J 0
(325 2525);
DISPLAY 0.404255 (325 2525);
FORCEPROP 1 LAST MATERIAL CHIP
J 0
(325 2500);
DISPLAY 0.404255 (325 2500);
FORCEPROP 1 LAST PACK_TYPE 0402LF
J 0
(325 2450);
DISPLAY 0.404255 (325 2450);
FORCEPROP 1 LAST TOLERANCE 1%
J 0
(325 2550);
DISPLAY 0.404255 (325 2550);
FORCEPROP 1 LAST VALUE 10
J 0
(325 2575);
DISPLAY 0.404255 (325 2575);
FORCEPROP 2 LAST ROOM NIC1_P3V3_BOM1
J 0
(325 2650);
DISPLAY 0.510638 (325 2650);
FORCEPROP 1 LAST LOCATION PR3782
J 0
(325 2600);
DISPLAY 0.638298 (325 2600);
FORCEPROP 1 LASTPIN (275 2625) $PN 1
J 0
(280 2587);
DISPLAY 0.787234 (280 2587);
PAINT MONO (280 2587);
FORCEPROP 1 LASTPIN (275 2425) $PN 2
J 0
(280 2435);
DISPLAY 0.787234 (280 2435);
PAINT MONO (280 2435);
FORCEPROP 1 LAST PATH I92
J 0
(325 2700);
DISPLAY 0.978723 (325 2700);
PAINT WHITE (325 2700);
DISPLAY INVISIBLE (325 2700);
FORCEPROP 2 LAST CDS_LIB pure_quanta
J 0
(275 2525);
DISPLAY INVISIBLE (275 2525);
FORCEPROP 0 LAST $SEC 1
J 0
(325 2650);
DISPLAY 0.680851 (325 2650);
PAINT MONO (325 2650);
DISPLAY INVISIBLE (325 2650);
FORCEPROP 0 LAST CDS_SEC 1
J 0
(325 2650);
DISPLAY 1.021277 (325 2650);
DISPLAY INVISIBLE (325 2650);
FORCEADD SCHOTTKY_AC..1
R 1
(2650 425);
FORCEPROP 1 LAST PART_NUMBER BC000340Z30
J 0
(2700 350);
DISPLAY 0.595745 (2700 350);
PAINT GREEN (2700 350);
DISPLAY INVISIBLE (2700 350);
FORCEPROP 1 LAST MATERIAL IC
J 0
(2700 325);
DISPLAY 0.723404 (2700 325);
PAINT GREEN (2700 325);
FORCEPROP 2 LAST VALUE B340A-13-F
J 0
(2700 400);
DISPLAY 0.638298 (2700 400);
FORCEPROP 1 LAST LOCATION PD108
J 0
(2700 450);
DISPLAY 0.723404 (2700 450);
PAINT GREEN (2700 450);
FORCEPROP 0 LASTPIN (2650 300) $PN A
R 1
J 2
(2640 335);
DISPLAY 0.808511 (2640 335);
FORCEPROP 0 LASTPIN (2650 550) $PN C
R 1
J 0
(2640 510);
DISPLAY 0.808511 (2640 510);
FORCEPROP 0 LAST PART_TYPE SMLF
J 0
(2700 600);
DISPLAY 1.021277 (2700 600);
DISPLAY INVISIBLE (2700 600);
FORCEPROP 1 LAST NEEDS_NO_SIZE TRUE
R 1
J 0
(2700 500);
DISPLAY 0.468085 (2700 500);
PAINT GREEN (2700 500);
DISPLAY INVISIBLE (2700 500);
FORCEPROP 2 LAST CDS_LIB pure_quanta
R 1
J 0
(2650 425);
DISPLAY INVISIBLE (2650 425);
FORCEPROP 1 LAST CDS_LMAN_SYM_OUTLINE -75,50,75,-50
R 1
J 0
(2650 425);
DISPLAY 0.468085 (2650 425);
PAINT GREEN (2650 425);
DISPLAY INVISIBLE (2650 425);
FORCEPROP 1 LAST PATH I93
R 1
J 0
(2650 425);
DISPLAY 0.723404 (2650 425);
PAINT GREEN (2650 425);
DISPLAY INVISIBLE (2650 425);
FORCEPROP 0 LAST $SEC 1
R 1
J 0
(2700 500);
DISPLAY INVISIBLE (2700 500);
FORCEPROP 0 LAST CDS_SEC 1
R 1
J 0
(2700 500);
DISPLAY INVISIBLE (2700 500);
FORCEADD GND..1
(2275 1125);
FORCEPROP 3 LASTPIN (2275 1175) SIG_NAME GND\g
J 0
(2285 1185);
DISPLAY 0.659574 (2285 1185);
PAINT MONO (2285 1185);
DISPLAY INVISIBLE (2285 1185);
FORCEPROP 1 LAST HDL_POWER GND
J 0
(2275 1275);
DISPLAY 0.872340 (2275 1275);
PAINT GREEN (2275 1275);
DISPLAY INVISIBLE (2275 1275);
FORCEPROP 2 LAST CDS_LIB logical_power
J 0
(2275 1125);
DISPLAY INVISIBLE (2275 1125);
FORCEPROP 1 LAST SIZE 1B
J 0
(2350 1075);
DISPLAY 0.872340 (2350 1075);
PAINT GREEN (2350 1075);
DISPLAY INVISIBLE (2350 1075);
FORCEPROP 1 LAST PATH I94
J 0
(2350 1125);
DISPLAY 0.872340 (2350 1125);
PAINT AQUA (2350 1125);
DISPLAY INVISIBLE (2350 1125);
FORCEADD Q_RES..2
(2400 1450);
FORCEPROP 1 LAST PART_NUMBER CS24532FB03
J 0
(2440 1325);
DISPLAY 0.404255 (2440 1325);
DISPLAY INVISIBLE (2440 1325);
FORCEPROP 1 LAST TOLERANCE 1%
J 0
(2445 1475);
DISPLAY 0.404255 (2445 1475);
FORCEPROP 1 LAST MATERIAL CHIP
J 0
(2440 1375);
DISPLAY 0.404255 (2440 1375);
FORCEPROP 1 LAST WATTAGE 1/16W
J 0
(2440 1425);
DISPLAY 0.404255 (2440 1425);
FORCEPROP 1 LAST PACK_TYPE 0402LF
J 0
(2440 1275);
DISPLAY 0.404255 (2440 1275);
FORCEPROP 2 LAST ROOM NIC1_P3V3_BOM1
J 0
(2450 1625);
DISPLAY 0.510638 (2450 1625);
FORCEPROP 1 LAST VALUE 4.53K
J 0
(2445 1525);
DISPLAY 0.404255 (2445 1525);
FORCEPROP 1 LAST LOCATION PR3824
J 0
(2445 1575);
DISPLAY 0.638298 (2445 1575);
FORCEPROP 1 LASTPIN (2400 1550) $PN 1
J 0
(2405 1512);
DISPLAY 0.787234 (2405 1512);
PAINT MONO (2405 1512);
FORCEPROP 1 LASTPIN (2400 1350) $PN 2
J 0
(2405 1360);
DISPLAY 0.787234 (2405 1360);
PAINT MONO (2405 1360);
FORCEPROP 1 LAST PATH I95
J 0
(2450 1625);
DISPLAY 0.978723 (2450 1625);
PAINT WHITE (2450 1625);
DISPLAY INVISIBLE (2450 1625);
FORCEPROP 2 LAST CDS_LIB pure_quanta
J 0
(2400 1450);
DISPLAY INVISIBLE (2400 1450);
FORCEPROP 0 LAST $SEC 1
J 0
(2450 1625);
DISPLAY 0.680851 (2450 1625);
PAINT MONO (2450 1625);
DISPLAY INVISIBLE (2450 1625);
FORCEPROP 0 LAST CDS_SEC 1
J 0
(2450 1625);
DISPLAY 1.021277 (2450 1625);
DISPLAY INVISIBLE (2450 1625);
FORCEADD Q_CAP..1
R 1
(2975 1900);
FORCEPROP 1 LAST PART_NUMBER CH2686K1B01
J 0
(3025 1925);
DISPLAY 0.638298 (3025 1925);
DISPLAY INVISIBLE (3025 1925);
FORCEPROP 1 LAST VALUE 6800PF
J 0
(2875 1975);
DISPLAY 0.638298 (2875 1975);
FORCEPROP 1 LAST VOLTAGE 50V
J 0
(3075 1975);
DISPLAY 0.638298 (3075 1975);
FORCEPROP 1 LAST PACK_TYPE C0402
J 0
(2750 1850);
DISPLAY 0.638298 (2750 1850);
FORCEPROP 2 LAST ROOM NIC1_P3V3_BOM1
J 0
(3075 2025);
DISPLAY 0.319149 (3075 2025);
FORCEPROP 1 LAST LOCATION PC2151
J 0
(2700 1900);
DISPLAY 0.638298 (2700 1900);
FORCEPROP 1 LASTPIN (2875 1900) $PN 1
R 1
J 0
(2895 1910);
DISPLAY 0.787234 (2895 1910);
PAINT MONO (2895 1910);
FORCEPROP 1 LASTPIN (3075 1900) $PN 2
R 1
J 0
(3095 1910);
DISPLAY 0.787234 (3095 1910);
PAINT MONO (3095 1910);
FORCEPROP 1 LAST PATH I96
R 1
J 0
(2825 1950);
DISPLAY 0.978723 (2825 1950);
PAINT WHITE (2825 1950);
DISPLAY INVISIBLE (2825 1950);
FORCEPROP 2 LAST CDS_LIB pure_quanta
R 1
J 0
(2975 1900);
DISPLAY INVISIBLE (2975 1900);
FORCEPROP 1 LAST MATERIAL X7R
R 1
J 0
(2975 1950);
DISPLAY 0.638298 (2975 1950);
DISPLAY INVISIBLE (2975 1950);
FORCEPROP 1 LAST TOLERANCE 10%
R 1
J 0
(3025 1950);
DISPLAY 0.638298 (3025 1950);
DISPLAY INVISIBLE (3025 1950);
FORCEPROP 0 LAST $SEC 1
R 1
J 0
(3075 2025);
DISPLAY 0.680851 (3075 2025);
PAINT MONO (3075 2025);
DISPLAY INVISIBLE (3075 2025);
FORCEPROP 0 LAST CDS_SEC 1
R 1
J 0
(3075 2025);
DISPLAY 1.021277 (3075 2025);
DISPLAY INVISIBLE (3075 2025);
FORCEADD Q_RES..1
(3050 1800);
FORCEPROP 1 LAST PART_NUMBER CS00002JB13
J 0
(2875 1750);
DISPLAY 0.595745 (2875 1750);
DISPLAY INVISIBLE (2875 1750);
FORCEPROP 1 LAST PACK_TYPE 0402LF
J 0
(3200 1750);
DISPLAY 0.595745 (3200 1750);
FORCEPROP 1 LAST MATERIAL CHIP
J 0
(2825 1800);
DISPLAY 0.595745 (2825 1800);
FORCEPROP 1 LAST TOLERANCE 5%
J 0
(3225 1800);
DISPLAY 0.595745 (3225 1800);
FORCEPROP 1 LAST VALUE 0
J 2
(3200 1800);
DISPLAY 0.595745 (3200 1800);
FORCEPROP 1 LAST WATTAGE 1/16W
J 2
(2850 1750);
DISPLAY 0.595745 (2850 1750);
FORCEPROP 2 LAST ROOM NIC1_P3V3_BOM1
J 0
(2850 1700);
DISPLAY 0.404255 (2850 1700);
FORCEPROP 1 LAST LOCATION R3832
J 0
(2700 1800);
DISPLAY 0.638298 (2700 1800);
FORCEPROP 1 LASTPIN (2950 1800) $PN 1
J 0
(2962 1812);
DISPLAY 0.787234 (2962 1812);
PAINT MONO (2962 1812);
FORCEPROP 1 LASTPIN (3150 1800) $PN 2
J 0
(3112 1812);
DISPLAY 0.787234 (3112 1812);
PAINT MONO (3112 1812);
FORCEPROP 1 LAST PATH I97
J 0
(3000 1950);
DISPLAY 0.978723 (3000 1950);
PAINT WHITE (3000 1950);
DISPLAY INVISIBLE (3000 1950);
FORCEPROP 2 LAST CDS_LIB pure_quanta
J 0
(3050 1800);
DISPLAY INVISIBLE (3050 1800);
FORCEPROP 0 LAST $SEC 1
J 0
(3000 1875);
DISPLAY 0.680851 (3000 1875);
PAINT MONO (3000 1875);
DISPLAY INVISIBLE (3000 1875);
FORCEPROP 0 LAST CDS_SEC 1
J 0
(3000 1875);
DISPLAY 1.021277 (3000 1875);
DISPLAY INVISIBLE (3000 1875);
FORCEADD Q_CAP..1
(3125 400);
FORCEPROP 1 LAST PART_NUMBER CH4104K1B00
J 0
(3175 250);
DISPLAY 0.638298 (3175 250);
DISPLAY INVISIBLE (3175 250);
FORCEPROP 1 LAST VALUE 0.1UF
J 0
(3175 450);
DISPLAY 0.638298 (3175 450);
FORCEPROP 1 LAST MATERIAL X7R
J 0
(3175 350);
DISPLAY 0.638298 (3175 350);
FORCEPROP 1 LAST PACK_TYPE 0402
J 0
(3175 300);
DISPLAY 0.638298 (3175 300);
FORCEPROP 1 LAST VOLTAGE 25V
J 0
(3175 400);
DISPLAY 0.638298 (3175 400);
FORCEPROP 1 LAST LOCATION PC2152
J 0
(3175 500);
DISPLAY 0.638298 (3175 500);
FORCEPROP 1 LASTPIN (3125 500) $PN 1
J 0
(3135 480);
DISPLAY 0.787234 (3135 480);
PAINT MONO (3135 480);
FORCEPROP 1 LASTPIN (3125 300) $PN 2
J 0
(3135 280);
DISPLAY 0.787234 (3135 280);
PAINT MONO (3135 280);
FORCEPROP 1 LAST TOLERANCE 10%
J 0
(3175 350);
DISPLAY 0.978723 (3175 350);
DISPLAY INVISIBLE (3175 350);
FORCEPROP 2 LAST CDS_LIB pure_quanta
J 0
(3125 400);
DISPLAY INVISIBLE (3125 400);
FORCEPROP 1 LAST PATH I98
J 0
(3175 550);
DISPLAY 0.978723 (3175 550);
PAINT WHITE (3175 550);
DISPLAY INVISIBLE (3175 550);
FORCEPROP 0 LAST $SEC 1
J 0
(3175 550);
DISPLAY 0.680851 (3175 550);
PAINT MONO (3175 550);
DISPLAY INVISIBLE (3175 550);
FORCEPROP 0 LAST CDS_SEC 1
J 0
(3175 550);
DISPLAY 1.021277 (3175 550);
DISPLAY INVISIBLE (3175 550);
FORCEADD VCCAUX15..1
(3450 75);
FORCEPROP 3 LASTPIN (3450 25) SIG_NAME P3V3_AUX\g
J 0
(3460 35);
DISPLAY 0.659574 (3460 35);
PAINT MONO (3460 35);
DISPLAY INVISIBLE (3460 35);
FORCEPROP 1 LAST HDL_POWER P3V3_AUX
J 1
(3450 125);
DISPLAY 0.723404 (3450 125);
PAINT GREEN (3450 125);
FORCEPROP 2 LAST CDS_LIB logical_power
J 0
(3450 75);
DISPLAY INVISIBLE (3450 75);
FORCEPROP 1 LAST PATH I99
J 0
(3500 100);
DISPLAY 0.872340 (3500 100);
PAINT AQUA (3500 100);
DISPLAY INVISIBLE (3500 100);
FORCEADD QUANTA_TITLE_BLOCK_C..1
(4625 -3375);
FORCEPROP 0 LAST CDS_CON_LAST_MODIFIED Fri Aug 25 14:02:31 2023
J 0
(2740 -3360);
DISPLAY INVISIBLE (2740 -3360);
FORCEPROP 1 LAST CUSTOM_TXT_CDS <CON_LAST_MODIFIED>
J 0
(2740 -3360);
DISPLAY 0.978723 (2740 -3360);
FORCEPROP 2 LAST CUSTOM_TXT_CDS <XR_PAGE_TITLE>
J 0
(-3265 1875);
DISPLAY 0.638298 (-3265 1875);
PAINT PINK (-3265 1875);
DISPLAY INVISIBLE (-3265 1875);
FORCEPROP 1 LAST CUSTOM_TXT_CDS <NAME_2>
J 0
(1450 -3325);
FORCEPROP 1 LAST CUSTOM_TXT_CDS <NAME_1>
J 0
(1450 -3200);
FORCEPROP 1 LAST CUSTOM_TXT_CDS <Q_NUMBER>
J 0
(3222 -3272);
DISPLAY 1.212766 (3222 -3272);
FORCEPROP 1 LAST CUSTOM_TXT_CDS <Q_PROJ>
J 0
(2243 -3273);
DISPLAY 1.212766 (2243 -3273);
FORCEPROP 1 LAST CUSTOM_TXT_CDS <Q_REV>
J 0
(4441 -3272);
DISPLAY 1.212766 (4441 -3272);
FORCEPROP 1 LAST CUSTOM_TXT_CDS <CON_PAGE_NUM> OF <CON_TOTAL_PAGES>
J 0
(4179 -3357);
DISPLAY 0.978723 (4179 -3357);
FORCEPROP 1 LAST Q_TITLE V3_2_OCP3.0 HSC(1/3)
J 0
(-4741 -3349);
DISPLAY 2.446809 (-4741 -3349);
PAINT GREEN (-4741 -3349);
FORCEPROP 1 LAST Q_DEPT 
J 1
(862 -3326);
DISPLAY 1.957447 (862 -3326);
PAINT GREEN (862 -3326);
FORCEPROP 2 LAST CDS_XR_PAGE_TITLE CR-162 : @S9S_MB_2U_LIB.S9S_MB_2U(SCH_1):PAGE162
J 0
(-3265 1875);
DISPLAY 0.638298 (-3265 1875);
PAINT PINK (-3265 1875);
DISPLAY INVISIBLE (-3265 1875);
FORCEPROP 2 LAST PAGE_BORDER TRUE
J 0
(-3265 1875);
DISPLAY 0.638298 (-3265 1875);
PAINT PINK (-3265 1875);
DISPLAY INVISIBLE (-3265 1875);
FORCEPROP 1 LAST CDS_LMAN_SYM_OUTLINE -9475,6775,100,-125
J 0
(4625 -3375);
DISPLAY 0.468085 (4625 -3375);
PAINT GREEN (4625 -3375);
DISPLAY INVISIBLE (4625 -3375);
FORCEPROP 2 LAST CDS_LIB pure_quanta
J 0
(4625 -3375);
DISPLAY INVISIBLE (4625 -3375);
FORCEPROP 1 LAST COMMENT_BODY TRUE
J 0
(4637 -3388);
DISPLAY 0.978723 (4637 -3388);
PAINT GREEN (4637 -3388);
DISPLAY INVISIBLE (4637 -3388);
FORCEADD DNS..2
(-3875 -975);
PAINT RED (-3875 -975);
FORCEPROP 1 LAST COMMENT_BODY TRUE
R 1
J 0
(-3800 -1200);
DISPLAY 0.872340 (-3800 -1200);
PAINT GREEN (-3800 -1200);
DISPLAY INVISIBLE (-3800 -1200);
FORCEPROP 2 LAST CDS_LIB mstr_misc
J 0
(-3875 -975);
DISPLAY INVISIBLE (-3875 -975);
FORCEADD DNS..2
(-2975 -925);
PAINT RED (-2975 -925);
FORCEPROP 1 LAST COMMENT_BODY TRUE
R 1
J 0
(-2900 -1150);
DISPLAY 0.872340 (-2900 -1150);
PAINT GREEN (-2900 -1150);
DISPLAY INVISIBLE (-2900 -1150);
FORCEPROP 2 LAST CDS_LIB mstr_misc
J 0
(-2975 -925);
DISPLAY INVISIBLE (-2975 -925);
FORCEADD DNS..2
(-2950 -350);
PAINT RED (-2950 -350);
FORCEPROP 1 LAST COMMENT_BODY TRUE
R 1
J 0
(-2875 -575);
DISPLAY 0.872340 (-2875 -575);
PAINT GREEN (-2875 -575);
DISPLAY INVISIBLE (-2875 -575);
FORCEPROP 2 LAST CDS_LIB mstr_misc
J 0
(-2950 -350);
DISPLAY INVISIBLE (-2950 -350);
FORCEADD DNS..2
(-2325 -600);
PAINT RED (-2325 -600);
FORCEPROP 1 LAST COMMENT_BODY TRUE
R 1
J 0
(-2250 -825);
DISPLAY 0.872340 (-2250 -825);
PAINT GREEN (-2250 -825);
DISPLAY INVISIBLE (-2250 -825);
FORCEPROP 2 LAST CDS_LIB mstr_misc
J 0
(-2325 -600);
DISPLAY INVISIBLE (-2325 -600);
FORCEADD DNS..2
(-150 -1050);
PAINT RED (-150 -1050);
FORCEPROP 1 LAST COMMENT_BODY TRUE
R 1
J 0
(-75 -1275);
DISPLAY 0.872340 (-75 -1275);
PAINT GREEN (-75 -1275);
DISPLAY INVISIBLE (-75 -1275);
FORCEPROP 2 LAST CDS_LIB mstr_misc
J 0
(-150 -1050);
DISPLAY INVISIBLE (-150 -1050);
FORCEADD DNS..2
(-725 -425);
PAINT RED (-725 -425);
FORCEPROP 1 LAST COMMENT_BODY TRUE
R 1
J 0
(-650 -650);
DISPLAY 0.872340 (-650 -650);
PAINT GREEN (-650 -650);
DISPLAY INVISIBLE (-650 -650);
FORCEPROP 2 LAST CDS_LIB mstr_misc
J 0
(-725 -425);
DISPLAY INVISIBLE (-725 -425);
FORCEADD DNS..2
(-150 -775);
PAINT RED (-150 -775);
FORCEPROP 1 LAST COMMENT_BODY TRUE
R 1
J 0
(-75 -1000);
DISPLAY 0.872340 (-75 -1000);
PAINT GREEN (-75 -1000);
DISPLAY INVISIBLE (-75 -1000);
FORCEPROP 2 LAST CDS_LIB mstr_misc
J 0
(-150 -775);
DISPLAY INVISIBLE (-150 -775);
FORCEADD DNS..2
(-150 -100);
PAINT RED (-150 -100);
FORCEPROP 1 LAST COMMENT_BODY TRUE
R 1
J 0
(-75 -325);
DISPLAY 0.872340 (-75 -325);
PAINT GREEN (-75 -325);
DISPLAY INVISIBLE (-75 -325);
FORCEPROP 2 LAST CDS_LIB mstr_misc
J 0
(-150 -100);
DISPLAY INVISIBLE (-150 -100);
FORCEADD DNS..2
(700 -1025);
PAINT RED (700 -1025);
FORCEPROP 1 LAST COMMENT_BODY TRUE
R 1
J 0
(775 -1250);
DISPLAY 0.872340 (775 -1250);
PAINT GREEN (775 -1250);
DISPLAY INVISIBLE (775 -1250);
FORCEPROP 2 LAST CDS_LIB mstr_misc
J 0
(700 -1025);
DISPLAY INVISIBLE (700 -1025);
FORCEADD DNS..2
(400 -500);
PAINT RED (400 -500);
FORCEPROP 1 LAST COMMENT_BODY TRUE
R 1
J 0
(475 -725);
DISPLAY 0.872340 (475 -725);
PAINT GREEN (475 -725);
DISPLAY INVISIBLE (475 -725);
FORCEPROP 2 LAST CDS_LIB mstr_misc
J 0
(400 -500);
DISPLAY INVISIBLE (400 -500);
FORCEADD DNS..2
(175 -250);
PAINT RED (175 -250);
FORCEPROP 1 LAST COMMENT_BODY TRUE
R 1
J 0
(250 -475);
DISPLAY 0.872340 (250 -475);
PAINT GREEN (250 -475);
DISPLAY INVISIBLE (250 -475);
FORCEPROP 2 LAST CDS_LIB mstr_misc
J 0
(175 -250);
DISPLAY INVISIBLE (175 -250);
FORCEADD DNS..2
(1425 -325);
PAINT RED (1425 -325);
FORCEPROP 1 LAST COMMENT_BODY TRUE
R 1
J 0
(1500 -550);
DISPLAY 0.872340 (1500 -550);
PAINT GREEN (1500 -550);
DISPLAY INVISIBLE (1500 -550);
FORCEPROP 2 LAST CDS_LIB mstr_misc
J 0
(1425 -325);
DISPLAY INVISIBLE (1425 -325);
FORCEADD CAD_NOTE..1
(2825 -1075);
FORCEPROP 0 LAST S1 R3867/R3868 CO-LAYOUT
J 0
(2700 -1200);
DISPLAY 0.808511 (2700 -1200);
PAINT WHITE (2700 -1200);
FORCEPROP 1 LAST COMMENT_BODY TRUE
J 0
(2850 -975);
DISPLAY 0.978723 (2850 -975);
DISPLAY INVISIBLE (2850 -975);
FORCEPROP 2 LAST CDS_LIB logical_power
J 0
(2825 -1075);
DISPLAY INVISIBLE (2825 -1075);
FORCEADD DNS..2
(2300 -900);
PAINT RED (2300 -900);
FORCEPROP 1 LAST COMMENT_BODY TRUE
R 1
J 0
(2375 -1125);
DISPLAY 0.872340 (2375 -1125);
PAINT GREEN (2375 -1125);
DISPLAY INVISIBLE (2375 -1125);
FORCEPROP 2 LAST CDS_LIB mstr_misc
J 0
(2300 -900);
DISPLAY INVISIBLE (2300 -900);
FORCEADD DNS..2
(2275 -200);
PAINT RED (2275 -200);
FORCEPROP 1 LAST COMMENT_BODY TRUE
R 1
J 0
(2350 -425);
DISPLAY 0.872340 (2350 -425);
PAINT GREEN (2350 -425);
DISPLAY INVISIBLE (2350 -425);
FORCEPROP 2 LAST CDS_LIB mstr_misc
J 0
(2275 -200);
DISPLAY INVISIBLE (2275 -200);
FORCEADD DNS..2
(2575 -175);
PAINT RED (2575 -175);
FORCEPROP 1 LAST COMMENT_BODY TRUE
R 1
J 0
(2650 -400);
DISPLAY 0.872340 (2650 -400);
PAINT GREEN (2650 -400);
DISPLAY INVISIBLE (2650 -400);
FORCEPROP 2 LAST CDS_LIB mstr_misc
J 0
(2575 -175);
DISPLAY INVISIBLE (2575 -175);
FORCEADD DNS..2
(3075 -850);
PAINT RED (3075 -850);
FORCEPROP 1 LAST COMMENT_BODY TRUE
R 1
J 0
(3150 -1075);
DISPLAY 0.872340 (3150 -1075);
PAINT GREEN (3150 -1075);
DISPLAY INVISIBLE (3150 -1075);
FORCEPROP 2 LAST CDS_LIB mstr_misc
J 0
(3075 -850);
DISPLAY INVISIBLE (3075 -850);
FORCEADD DNS..2
(2925 -525);
PAINT RED (2925 -525);
FORCEPROP 1 LAST COMMENT_BODY TRUE
R 1
J 0
(3000 -750);
DISPLAY 0.872340 (3000 -750);
PAINT GREEN (3000 -750);
DISPLAY INVISIBLE (3000 -750);
FORCEPROP 2 LAST CDS_LIB mstr_misc
J 0
(2925 -525);
DISPLAY INVISIBLE (2925 -525);
FORCEADD DNS..2
(3075 -725);
PAINT RED (3075 -725);
FORCEPROP 1 LAST COMMENT_BODY TRUE
R 1
J 0
(3150 -950);
DISPLAY 0.872340 (3150 -950);
PAINT GREEN (3150 -950);
DISPLAY INVISIBLE (3150 -950);
FORCEPROP 2 LAST CDS_LIB mstr_misc
J 0
(3075 -725);
DISPLAY INVISIBLE (3075 -725);
FORCEADD DNS..2
(3275 -275);
PAINT RED (3275 -275);
FORCEPROP 1 LAST COMMENT_BODY TRUE
R 1
J 0
(3350 -500);
DISPLAY 0.872340 (3350 -500);
PAINT GREEN (3350 -500);
DISPLAY INVISIBLE (3350 -500);
FORCEPROP 2 LAST CDS_LIB mstr_misc
J 0
(3275 -275);
DISPLAY INVISIBLE (3275 -275);
FORCEADD DNS..2
(3700 -275);
PAINT RED (3700 -275);
FORCEPROP 1 LAST COMMENT_BODY TRUE
R 1
J 0
(3775 -500);
DISPLAY 0.872340 (3775 -500);
PAINT GREEN (3775 -500);
DISPLAY INVISIBLE (3775 -500);
FORCEPROP 2 LAST CDS_LIB mstr_misc
J 0
(3700 -275);
DISPLAY INVISIBLE (3700 -275);
FORCEADD DNS..2
(175 200);
PAINT RED (175 200);
FORCEPROP 1 LAST COMMENT_BODY TRUE
R 1
J 0
(250 -25);
DISPLAY 0.872340 (250 -25);
PAINT GREEN (250 -25);
DISPLAY INVISIBLE (250 -25);
FORCEPROP 2 LAST CDS_LIB mstr_misc
J 0
(175 200);
DISPLAY INVISIBLE (175 200);
FORCEADD DNS..2
(2400 2125);
PAINT RED (2400 2125);
FORCEPROP 1 LAST COMMENT_BODY TRUE
R 1
J 0
(2475 1900);
DISPLAY 0.872340 (2475 1900);
PAINT GREEN (2475 1900);
DISPLAY INVISIBLE (2475 1900);
FORCEPROP 2 LAST CDS_LIB mstr_misc
J 0
(2400 2125);
DISPLAY INVISIBLE (2400 2125);
WIRE 16 -1 (1675 -1625)(1675 -1675);
WIRE 16 -1 (3450 25)(3450 -25);
WIRE 16 -1 (-2550 -2100)(-2550 -2125);
WIRE 16 -1 (-2550 -1200)(-2550 -1225);
WIRE 16 -1 (-2975 -150)(-2975 -250);
WIRE 16 -1 (-500 -2600)(-500 -2650);
WIRE 16 -1 (-500 -1700)(-500 -1750);
WIRE 16 -1 (-2325 2150)(-2325 2050);
WIRE 16 -1 (-750 500)(-750 425);
WIRE 16 -1 (-400 2825)(-400 2750);
WIRE 16 -1 (3950 650)(3950 600);
WIRE 16 -1 (3600 2375)(3600 2325);
WIRE 16 -1 (3850 2975)(3850 2925);
WIRE 16 -1 (-2975 -1150)(-2975 -1250);
WIRE 16 -1 (-2300 -825)(-2300 -875);
WIRE 16 -1 (-1575 -2900)(-1575 -2650);
WIRE 16 -1 (-500 -2975)(-500 -2925);
WIRE 16 -1 (-500 -2075)(-500 -2025);
WIRE 16 -1 (-1575 -1975)(-1575 -1750);
WIRE 16 -1 (-175 -1150)(-175 -1250);
WIRE 16 -1 (-750 -125)(-750 -65);
WIRE 16 -1 (-2825 875)(-2825 800);
WIRE 16 -1 (-2325 1150)(-2325 1050);
WIRE 16 -1 (-1550 1225)(-1550 1125);
WIRE 16 -1 (-50 1175)(-50 1075);
WIRE 16 -1 (-400 2425)(-400 2300);
WIRE 16 -1 (675 -1275)(675 -1225);
WIRE 16 -1 (150 -525)(150 -550);
WIRE 16 -1 (150 -325)(150 -525);
WIRE 16 -1 (150 -525)(275 -525);
WIRE 16 -1 (2150 -1150)(2150 -1075);
WIRE 16 -1 (3000 -425)(3000 -450);
WIRE 16 -1 (2925 -425)(3000 -425);
WIRE 16 -1 (275 1800)(275 1775);
WIRE 16 -1 (275 1800)(400 1800);
WIRE 16 -1 (275 2000)(275 1800);
WIRE 16 -1 (800 1050)(800 1100);
WIRE 16 -1 (2275 1175)(2275 1250);
WIRE 16 -1 (3950 150)(3950 225);
WIRE 16 -1 (3150 1900)(3150 1875);
WIRE 16 -1 (3075 1900)(3150 1900);
WIRE 16 -1 (3850 2475)(3850 2550);
WIRE 16 -1 (-900 350)(-900 425);
WIRE 16 -1 (-900 425)(-750 425);
WIRE 16 -1 (-525 425)(-750 425);
WIRE 16 -1 (-525 425)(-525 300);
WIRE 16 -1 (-175 425)(-175 0);
WIRE 16 -1 (-525 425)(-175 425);
WIRE 16 -1 (-175 425)(150 425);
WIRE 16 -1 (150 425)(150 300);
WIRE 16 -1 (925 425)(150 425);
WIRE 16 -1 (925 -25)(1025 -25);
WIRE 16 -1 (925 425)(925 -25);
WIRE 16 -1 (925 -25)(925 -75);
WIRE 16 -1 (925 -75)(1025 -75);
WIRE 16 -1 (925 -75)(925 -125);
WIRE 16 -1 (925 -125)(1025 -125);
WIRE 16 -1 (925 -125)(925 -175);
WIRE 16 -1 (925 -175)(1025 -175);
WIRE 16 -1 (925 -175)(925 -225);
WIRE 16 -1 (925 -225)(1025 -225);
WIRE 16 -1 (925 -225)(925 -275);
WIRE 16 -1 (925 -275)(1025 -275);
WIRE 16 -1 (925 -275)(925 -325);
WIRE 16 -1 (925 -325)(1025 -325);
WIRE 16 -1 (1825 -725)(2275 -725);
WIRE 16 -1 (2275 -800)(2275 -725);
FORCEPROP 2 LAST SIG_NAME P12V_OCP_SENSE_2
J 0
(1890 -715);
DISPLAY 0.574468 (1890 -715);
WIRE 16 -1 (2275 -725)(2600 -725);
WIRE 16 -1 (2600 -725)(2950 -725);
WIRE 16 -1 (2600 -725)(2600 -850);
WIRE 16 -1 (2600 -850)(2950 -850);
WIRE 16 2175 (2650 -675)(3375 -675);
WIRE 16 2175 (3375 -675)(3375 -975);
WIRE 16 2175 (2650 -675)(2650 -975);
WIRE 16 2175 (2650 -975)(3375 -975);
WIRE 16 -1 (675 -1225)(675 -1125);
WIRE 16 -1 (1000 -1225)(675 -1225);
WIRE 16 -1 (1000 -925)(1000 -1225);
WIRE 16 -1 (1025 -925)(1000 -925);
WIRE 16 -1 (1825 -625)(3250 -625);
FORCEPROP 2 LAST SIG_NAME P12V_OCP_FAULT_2
J 0
(1890 -615);
DISPLAY 0.574468 (1890 -615);
WIRE 16 -1 (3250 -625)(3250 -375);
WIRE 16 -1 (1825 -525)(2800 -525);
FORCEPROP 2 LAST SIG_NAME P12V_OCP_PWRGD_2
J 0
(1890 -515);
DISPLAY 0.574468 (1890 -515);
WIRE 16 -1 (675 -825)(675 -925);
WIRE 16 -1 (1025 -825)(675 -825);
FORCEPROP 2 LAST SIG_NAME P12V_OCP_CB_2
J 0
(590 -815);
DISPLAY 0.574468 (590 -815);
WIRE 16 -1 (-175 -925)(-175 -950);
WIRE 16 -1 (-175 -875)(-175 -925);
WIRE 16 -1 (-175 -925)(125 -925);
WIRE 16 -1 (125 -925)(125 -725);
WIRE 16 -1 (125 -725)(1025 -725);
FORCEPROP 2 LAST SIG_NAME P12V_OCP_OV_2
J 0
(590 -715);
DISPLAY 0.574468 (590 -715);
WIRE 16 -1 (475 -525)(1025 -525);
FORCEPROP 2 LAST SIG_NAME P12V_OCP_REG_2
J 0
(565 -515);
DISPLAY 0.574468 (565 -515);
WIRE 16 -1 (500 -425)(1025 -425);
FORCEPROP 2 LAST SIG_NAME P12V_OCP_VCC_2
J 0
(565 -415);
DISPLAY 0.574468 (565 -415);
WIRE 16 -1 (500 0)(500 -425);
WIRE 16 -1 (500 0)(150 0);
WIRE 16 -1 (150 100)(150 0);
WIRE 16 -1 (150 0)(150 -125);
WIRE 16 -1 (1825 -325)(2132 -325);
WIRE 16 -1 (1825 -275)(2132 -275);
WIRE 16 -1 (2132 -325)(2132 -275);
WIRE 16 -1 (2132 -225)(1825 -225);
WIRE 16 -1 (2132 -275)(2132 -225);
WIRE 16 -1 (1825 -175)(2132 -175);
WIRE 16 -1 (2132 -225)(2132 -175);
WIRE 16 -1 (1825 -125)(2132 -125);
WIRE 16 -1 (2132 -175)(2132 -125);
WIRE 16 -1 (1825 -75)(2132 -75);
WIRE 16 -1 (2132 -125)(2132 -75);
WIRE 16 -1 (1825 -25)(2132 -25);
WIRE 16 -1 (2132 -75)(2132 -25);
WIRE 16 -1 (2550 -25)(2550 -100);
WIRE 16 -1 (2132 -25)(2250 -25);
WIRE 16 -1 (2250 -100)(2250 -25);
WIRE 16 -1 (2250 -25)(2345 -25);
WIRE 16 -1 (2345 -25)(2550 -25);
WIRE 16 -1 (2345 600)(2345 -25);
WIRE 16 -1 (2345 600)(2650 600);
WIRE 16 -1 (2650 600)(2650 550);
WIRE 16 -1 (3125 600)(2650 600);
WIRE 16 -1 (3125 500)(3125 600);
WIRE 16 -1 (3550 600)(3550 500);
WIRE 16 -1 (3550 600)(3125 600);
WIRE 16 -1 (3950 600)(3550 600);
WIRE 16 -1 (3950 500)(3950 600);
WIRE 16 -1 (600 1800)(1150 1800);
FORCEPROP 2 LAST SIG_NAME P3V3_OCP_REG_2
J 0
(690 1810);
DISPLAY 0.574468 (690 1810);
WIRE 16 -1 (625 1900)(1150 1900);
FORCEPROP 2 LAST SIG_NAME P3V3_OCP_VCC_2
J 0
(690 1910);
DISPLAY 0.574468 (690 1910);
WIRE 16 -1 (275 2325)(275 2200);
WIRE 16 -1 (275 2425)(275 2325);
WIRE 16 -1 (625 2325)(625 1900);
WIRE 16 -1 (625 2325)(275 2325);
WIRE 16 -1 (1050 2000)(1150 2000);
WIRE 16 -1 (1050 2050)(1050 2000);
WIRE 16 -1 (1050 2050)(1150 2050);
WIRE 16 -1 (1050 2100)(1050 2050);
WIRE 16 -1 (1050 2100)(1150 2100);
WIRE 16 -1 (1050 2150)(1050 2100);
WIRE 16 -1 (1050 2150)(1150 2150);
WIRE 16 -1 (1050 2200)(1050 2150);
WIRE 16 -1 (1050 2200)(1150 2200);
WIRE 16 -1 (1050 2250)(1050 2200);
WIRE 16 -1 (1050 2250)(1150 2250);
WIRE 16 -1 (1050 2300)(1050 2250);
WIRE 16 -1 (1050 2300)(1150 2300);
WIRE 16 -1 (1050 2750)(1050 2300);
WIRE 16 -1 (275 2750)(275 2625);
WIRE 16 -1 (1050 2750)(275 2750);
WIRE 16 -1 (-50 2750)(-50 2375);
WIRE 16 -1 (-50 2750)(275 2750);
WIRE 16 -1 (-400 2750)(-400 2625);
WIRE 16 -1 (-400 2750)(-50 2750);
WIRE 16 -1 (1950 1800)(2950 1800);
FORCEPROP 2 LAST SIG_NAME P3V3_OCP_PWRGD_2
J 0
(2015 1810);
DISPLAY 0.574468 (2015 1810);
WIRE 16 -1 (1950 1700)(3400 1700);
FORCEPROP 2 LAST SIG_NAME P3V3_OCP_FAULT_2
J 0
(2015 1710);
DISPLAY 0.574468 (2015 1710);
WIRE 16 -1 (3400 1700)(3400 2000);
WIRE 16 -1 (2400 1350)(2400 1250);
WIRE 16 -1 (1950 1500)(2175 1500);
WIRE 16 -1 (2275 1250)(2400 1250);
WIRE 16 -1 (1950 1400)(2125 1400);
WIRE 16 -1 (2175 1250)(2275 1250);
WIRE 16 -1 (2175 1500)(2175 1250);
WIRE 16 -1 (1950 1350)(2075 1350);
WIRE 16 -1 (2175 1250)(2125 1250);
WIRE 16 -1 (2125 1400)(2125 1250);
WIRE 16 -1 (2075 1250)(2125 1250);
WIRE 16 -1 (2075 1350)(2075 1250);
WIRE 16 -1 (2025 1250)(2075 1250);
WIRE 16 -1 (2025 1250)(2025 1300);
WIRE 16 -1 (2025 1300)(1950 1300);
WIRE 16 -1 (2375 1900)(1950 1900);
FORCEPROP 2 LAST SIG_NAME P3V3_OCP_GATE_2
J 0
(2015 1910);
DISPLAY 0.574468 (2015 1910);
WIRE 16 -1 (2375 2025)(2375 1900);
WIRE 16 -1 (2375 1900)(2650 1900);
WIRE 16 -1 (2650 2050)(2650 1900);
WIRE 16 -1 (2875 1900)(2650 1900);
WIRE 16 -1 (2250 -425)(1825 -425);
FORCEPROP 2 LAST SIG_NAME P12V_OCP_GATE_2
J 0
(1890 -415);
DISPLAY 0.574468 (1890 -415);
WIRE 16 -1 (2250 -300)(2250 -425);
WIRE 16 -1 (2550 -425)(2250 -425);
WIRE 16 -1 (2550 -300)(2550 -425);
WIRE 16 -1 (2725 -425)(2550 -425);
WIRE 16 -1 (3150 -850)(4250 -850);
FORCEPROP 2 LAST SIG_NAME P12V_OCP_V3_2_ISENSE_MAM_TIC
J 0
(3390 -840);
DISPLAY 0.574468 (3390 -840);
WIRE 16 -1 (1675 -1975)(1675 -2150);
WIRE 16 -1 (1675 -2150)(2700 -2150);
FORCEPROP 0 LAST CDS_PHYS_NET_NAME HP_LVC3_OCP_V3_2_ATTN_OUT_SW_N
J 0
(2590 -2108);
PAINT MONO (2590 -2108);
DISPLAY INVISIBLE (2590 -2108);
WIRE 16 -1 (525 -2150)(1675 -2150);
FORCEPROP 2 LAST SIG_NAME HP_LVC3_OCP_V3_2_ATTN_OUT_SW_N
J 0
(840 -2140);
DISPLAY 0.553191 (840 -2140);
PAINT WHITE (840 -2140);
WIRE 16 -1 (1675 -1675)(1675 -1775);
WIRE 16 -1 (1675 -1675)(1900 -1675);
WIRE 16 -1 (1900 -1775)(1900 -1675);
WIRE 16 -1 (1900 -1675)(2250 -1675);
WIRE 16 -1 (2250 -1675)(2250 -1800);
WIRE 16 -1 (2275 -1000)(2275 -1075);
WIRE 16 -1 (1825 -825)(2050 -825);
WIRE 16 -1 (2150 -1075)(2275 -1075);
WIRE 16 -1 (2050 -1075)(2150 -1075);
WIRE 16 -1 (2050 -825)(2050 -1075);
WIRE 16 -1 (1825 -925)(2000 -925);
WIRE 16 -1 (1825 -975)(1950 -975);
WIRE 16 -1 (2000 -925)(2000 -1075);
WIRE 16 -1 (2050 -1075)(2000 -1075);
WIRE 16 -1 (1950 -1075)(2000 -1075);
WIRE 16 -1 (1950 -975)(1950 -1075);
WIRE 16 -1 (1900 -1075)(1950 -1075);
WIRE 16 -1 (1900 -1075)(1900 -1025);
WIRE 16 -1 (1900 -1025)(1825 -1025);
WIRE 16 -1 (3000 -525)(3675 -525);
WIRE 16 -1 (3675 -525)(4100 -525);
WIRE 16 -1 (3675 -375)(3675 -525);
FORCEPROP 2 LAST SIG_NAME HP_LVC3_OCP_V3_2_P12V_PWRGD
J 0
(3390 -515);
DISPLAY 0.574468 (3390 -515);
WIRE 16 -1 (3250 -25)(3250 -175);
WIRE 16 -1 (3450 -25)(3250 -25);
WIRE 16 -1 (3675 -25)(3450 -25);
WIRE 16 -1 (3675 -25)(3675 -175);
WIRE 16 -1 (3800 2325)(3800 2200);
WIRE 16 -1 (3800 2325)(3600 2325);
WIRE 16 -1 (3400 2325)(3400 2200);
WIRE 16 -1 (3400 2325)(3600 2325);
WIRE 16 -1 (3850 2825)(3850 2925);
WIRE 16 -1 (3275 2825)(3275 2925);
WIRE 16 -1 (3850 2925)(3275 2925);
WIRE 16 -1 (2775 2925)(2775 2875);
WIRE 16 -1 (2775 2925)(3275 2925);
WIRE 16 -1 (2650 2300)(2650 2250);
WIRE 16 -1 (2470 2925)(2775 2925);
WIRE 16 -1 (2470 2925)(2470 2300);
WIRE 16 -1 (2470 2300)(2650 2300);
WIRE 16 -1 (2375 2225)(2375 2300);
WIRE 16 -1 (2375 2300)(2470 2300);
WIRE 16 -1 (1950 2300)(2257 2300);
WIRE 16 -1 (2257 2300)(2375 2300);
WIRE 16 -1 (1950 2250)(2257 2250);
WIRE 16 -1 (2257 2250)(2257 2300);
WIRE 16 -1 (1950 2200)(2257 2200);
WIRE 16 -1 (2257 2200)(2257 2250);
WIRE 16 -1 (1950 2150)(2257 2150);
WIRE 16 -1 (2257 2150)(2257 2200);
WIRE 16 -1 (2257 2100)(1950 2100);
WIRE 16 -1 (2257 2100)(2257 2150);
WIRE 16 -1 (1950 2050)(2257 2050);
WIRE 16 -1 (2257 2050)(2257 2100);
WIRE 16 -1 (2257 2000)(2257 2050);
WIRE 16 -1 (1950 2000)(2257 2000);
WIRE 16 -1 (3850 2550)(3850 2625);
WIRE 16 -1 (3275 2550)(3275 2625);
WIRE 16 -1 (3850 2550)(3275 2550);
WIRE 16 -1 (2775 2550)(3275 2550);
WIRE 16 -1 (2775 2625)(2775 2550);
WIRE 16 -1 (3800 2000)(3800 1800);
WIRE 16 -1 (3800 1800)(4150 1800);
WIRE 16 -1 (3150 1800)(3800 1800);
FORCEPROP 2 LAST SIG_NAME OCP_V3_2_P3V3_PWRGD
J 0
(3515 1810);
DISPLAY 0.574468 (3515 1810);
WIRE 16 -1 (3950 225)(3950 300);
WIRE 16 -1 (3550 225)(3550 300);
WIRE 16 -1 (3950 225)(3550 225);
WIRE 16 -1 (3125 225)(3125 300);
WIRE 16 -1 (3550 225)(3125 225);
WIRE 16 -1 (2650 225)(3125 225);
WIRE 16 -1 (2650 300)(2650 225);
WIRE 16 -1 (2400 1550)(2400 1600);
FORCEPROP 2 LAST SIG_NAME P3V3_OCP_SENSE_2
J 0
(2015 1610);
DISPLAY 0.574468 (2015 1610);
WIRE 16 -1 (1950 1600)(2400 1600);
WIRE 16 -1 (800 1100)(800 1200);
WIRE 16 -1 (1125 1100)(800 1100);
WIRE 16 -1 (1125 1400)(1125 1100);
WIRE 16 -1 (1150 1400)(1125 1400);
WIRE 16 -1 (800 1500)(800 1400);
WIRE 16 -1 (1150 1500)(800 1500);
FORCEPROP 2 LAST SIG_NAME P3V3_OCP_CB_2
J 0
(715 1510);
DISPLAY 0.574468 (715 1510);
WIRE 16 -1 (250 1600)(1150 1600);
FORCEPROP 2 LAST SIG_NAME P3V3_OCP_OV_2
J 0
(715 1610);
DISPLAY 0.574468 (715 1610);
WIRE 16 -1 (250 1400)(250 1600);
WIRE 16 -1 (-50 1400)(-50 1375);
WIRE 16 -1 (-50 1450)(-50 1400);
WIRE 16 -1 (-50 1400)(250 1400);
WIRE 16 -1 (3150 -725)(4250 -725);
FORCEPROP 2 LAST SIG_NAME P12V_OCP_V3_2_ISENSE_MAM_MAM
J 0
(3390 -715);
DISPLAY 0.574468 (3390 -715);
WIRE 16 -1 (2250 -2475)(475 -2475);
FORCEPROP 2 LAST SIG_NAME HP_LVC3_OCP_V3_2_PRSNT2_PLD_N
J 0
(790 -2465);
DISPLAY 0.553191 (790 -2465);
PAINT WHITE (790 -2465);
WIRE 16 -1 (2700 -2475)(2250 -2475);
FORCEPROP 0 LAST CDS_PHYS_NET_NAME HP_LVC3_OCP_V3_2_PRSNT2_PLD_N
J 0
(2590 -2433);
PAINT MONO (2590 -2433);
DISPLAY INVISIBLE (2590 -2433);
WIRE 16 -1 (2250 -2000)(2250 -2475);
WIRE 16 -1 (1900 -1975)(1900 -2300);
WIRE 16 -1 (1900 -2300)(2700 -2300);
WIRE 16 -1 (500 -2300)(1900 -2300);
FORCEPROP 0 LAST CDS_PHYS_NET_NAME HP_LVC3_OCP_V3_2_PRSNT2_N
J 0
(1865 -2258);
PAINT MONO (1865 -2258);
DISPLAY INVISIBLE (1865 -2258);
FORCEPROP 2 LAST SIG_NAME HP_LVC3_OCP_V3_2_PRSNT2_N
J 0
(815 -2290);
DISPLAY 0.553191 (815 -2290);
PAINT WHITE (815 -2290);
WIRE 16 -1 (-850 -1700)(-725 -1700);
WIRE 16 -1 (150 -2475)(275 -2475);
WIRE 16 -1 (150 -2150)(325 -2150);
WIRE 16 -1 (-725 -2700)(-850 -2700);
WIRE 16 -1 (150 -2300)(150 -2150);
WIRE 16 -1 (150 -2300)(150 -2475);
WIRE 16 -1 (150 -2300)(300 -2300);
FORCEPROP 0 LAST CDS_PHYS_NET_NAME HP_LVC3_OCP_V3_2_PRSNT2_N_R
J 0
(215 -2258);
PAINT MONO (215 -2258);
DISPLAY INVISIBLE (215 -2258);
WIRE 16 -1 (-725 -1800)(-850 -1800);
WIRE 16 -1 (-725 -1700)(-725 -1800);
WIRE 16 -1 (-725 -1800)(-725 -2300);
WIRE 16 -1 (-725 -2300)(150 -2300);
FORCEPROP 2 LAST SIG_NAME HP_LVC3_OCP_V3_2_PRSNT2_N_R
J 0
(-660 -2290);
DISPLAY 0.553191 (-660 -2290);
PAINT WHITE (-660 -2290);
WIRE 16 -1 (-725 -2600)(-850 -2600);
WIRE 16 -1 (-725 -2600)(-725 -2700);
WIRE 16 -1 (-725 -2600)(-725 -2300);
WIRE 16 -1 (-50 1700)(-50 1650);
WIRE 16 -1 (-50 1700)(1150 1700);
FORCEPROP 2 LAST SIG_NAME P3V3_OCP_UV_2
J 0
(715 1710);
DISPLAY 0.574468 (715 1710);
WIRE 16 -1 (-50 1700)(-50 1900);
WIRE 16 -1 (-50 2175)(-50 1900);
WIRE 16 -1 (-450 1900)(-50 1900);
WIRE 16 -1 (-650 1900)(-1550 1900);
FORCEPROP 2 LAST SIG_NAME P3V3_OCP_UV_2_R1
J 0
(-1435 1910);
DISPLAY 0.574468 (-1435 1910);
WIRE 16 -1 (-1550 1625)(-1550 1900);
WIRE 16 -1 (-1800 1675)(-1800 1375);
WIRE 16 -1 (-2325 1850)(-2325 1675);
WIRE 16 -1 (-2325 1675)(-1800 1675);
FORCEPROP 2 LAST SIG_NAME P3V3_OCP_2_EN_G
J 0
(-2285 1685);
DISPLAY 0.595745 (-2285 1685);
WIRE 16 -1 (-2325 1550)(-2325 1675);
WIRE 16 -1 (-2825 1075)(-2825 1300);
WIRE 16 -1 (-2825 1300)(-2575 1300);
WIRE 16 -1 (-3175 1300)(-2825 1300);
FORCEPROP 2 LAST SIG_NAME P3V3_OCP_EN_2_R
J 0
(-3035 1310);
DISPLAY 0.595745 (-3035 1310);
WIRE 16 -1 (-3375 1300)(-4075 1300);
FORCEPROP 2 LAST SIG_NAME HP_LVC3_OCP_V3_2_EN
J 0
(-4060 1310);
DISPLAY 0.638298 (-4060 1310);
WIRE 16 -1 (-4100 1000)(-4075 1000);
WIRE 16 -1 (-4075 1300)(-4075 1000);
WIRE 16 -1 (-4075 -1000)(-4000 -1000);
WIRE 16 -1 (-4075 -1000)(-4075 1000);
WIRE 16 2175 (-4305 2133)(-2602 2133);
WIRE 16 2175 (-2602 3033)(-2602 2133);
WIRE 16 2175 (-4305 3033)(-4305 2133);
WIRE 16 2175 (-4305 3033)(-2602 3033);
WIRE 16 -1 (-175 -625)(-175 -675);
WIRE 16 -1 (-175 -625)(1025 -625);
FORCEPROP 2 LAST SIG_NAME P12V_OCP_UV_2
J 0
(590 -615);
DISPLAY 0.574468 (590 -615);
WIRE 16 -1 (-175 -625)(-175 -425);
WIRE 16 -1 (-175 -200)(-175 -425);
WIRE 16 -1 (-675 -425)(-175 -425);
WIRE 16 -1 (-525 -65)(-525 100);
WIRE 16 -1 (-525 -65)(-750 -65);
WIRE 16 -1 (-900 -65)(-750 -65);
WIRE 16 -1 (-900 50)(-900 -65);
WIRE 16 -1 (-500 -1750)(-850 -1750);
WIRE 16 -1 (-500 -1825)(-500 -1750);
WIRE 16 -1 (-1575 -1750)(-1500 -1750);
WIRE 16 -1 (-500 -2650)(-850 -2650);
WIRE 16 -1 (-500 -2725)(-500 -2650);
WIRE 16 -1 (-1575 -2650)(-1500 -2650);
WIRE 16 -1 (-875 -425)(-2300 -425);
FORCEPROP 2 LAST SIG_NAME P12V_OCP_UV_2_R
J 0
(-1985 -415);
DISPLAY 0.574468 (-1985 -415);
WIRE 16 -1 (-2975 -450)(-2975 -675);
WIRE 16 -1 (-2975 -675)(-2550 -675);
FORCEPROP 2 LAST SIG_NAME P12V_OCP_2_EN_G
J 0
(-2935 -665);
DISPLAY 0.595745 (-2935 -665);
WIRE 16 -1 (-2975 -750)(-2975 -675);
WIRE 16 2175 (-2750 -1050)(-2075 -1050);
WIRE 16 2175 (-2075 -1050)(-2075 -1650);
WIRE 16 2175 (-2750 -1050)(-2750 -1650);
WIRE 16 2175 (-2750 -1650)(-2075 -1650);
WIRE 16 -1 (-2325 -1350)(-2325 -1225);
WIRE 16 -1 (-2325 -1225)(-2350 -1225);
WIRE 16 -1 (-2350 -1225)(-2350 -1250);
WIRE 16 -1 (-2350 -1225)(-2550 -1225);
WIRE 16 -1 (-2550 -1350)(-2550 -1225);
WIRE 16 -1 (-2550 -1700)(-2675 -1700);
WIRE 16 -1 (-2550 -1550)(-2550 -1700);
WIRE 16 -1 (-1500 -1700)(-2550 -1700);
FORCEPROP 0 LAST CDS_PHYS_NET_NAME OCP_V3_2_PRSNT0_R_N
J 0
(-1610 -1658);
PAINT MONO (-1610 -1658);
DISPLAY INVISIBLE (-1610 -1658);
FORCEPROP 2 LAST SIG_NAME OCP_V3_2_PRSNT0_R_N
J 0
(-2110 -1690);
DISPLAY 0.553191 (-2110 -1690);
PAINT WHITE (-2110 -1690);
WIRE 16 -1 (-2325 -1800)(-2675 -1800);
WIRE 16 -1 (-2325 -1550)(-2325 -1800);
WIRE 16 -1 (-1500 -1800)(-2325 -1800);
FORCEPROP 0 LAST CDS_PHYS_NET_NAME OCP_V3_2_PRSNT1_R_N
J 0
(-1610 -1758);
PAINT MONO (-1610 -1758);
DISPLAY INVISIBLE (-1610 -1758);
FORCEPROP 2 LAST SIG_NAME OCP_V3_2_PRSNT1_R_N
J 0
(-2110 -1790);
DISPLAY 0.553191 (-2110 -1790);
PAINT WHITE (-2110 -1790);
WIRE 16 -1 (-3800 -1000)(-3225 -1000);
FORCEPROP 2 LAST SIG_NAME P12V_OCP_EN_2_R
J 0
(-3685 -990);
DISPLAY 0.595745 (-3685 -990);
WIRE 16 2175 (-2750 -2500)(-2075 -2500);
WIRE 16 2175 (-2075 -1900)(-2075 -2500);
WIRE 16 2175 (-2750 -1900)(-2750 -2500);
WIRE 16 2175 (-2750 -1900)(-2075 -1900);
WIRE 16 -1 (-2325 -2250)(-2325 -2125);
WIRE 16 -1 (-2325 -2125)(-2550 -2125);
WIRE 16 -1 (-2550 -2250)(-2550 -2125);
WIRE 16 -1 (-2325 -2700)(-2675 -2700);
WIRE 16 -1 (-2325 -2450)(-2325 -2700);
WIRE 16 -1 (-1500 -2700)(-2325 -2700);
FORCEPROP 0 LAST CDS_PHYS_NET_NAME OCP_V3_2_PRSNT3_R_N
J 0
(-1610 -2658);
PAINT MONO (-1610 -2658);
DISPLAY INVISIBLE (-1610 -2658);
FORCEPROP 2 LAST SIG_NAME OCP_V3_2_PRSNT3_R_N
J 0
(-2110 -2690);
DISPLAY 0.553191 (-2110 -2690);
PAINT WHITE (-2110 -2690);
WIRE 16 -1 (-2550 -2600)(-2675 -2600);
WIRE 16 -1 (-2550 -2450)(-2550 -2600);
WIRE 16 -1 (-1500 -2600)(-2550 -2600);
FORCEPROP 0 LAST CDS_PHYS_NET_NAME OCP_V3_2_PRSNT2_R_N
J 0
(-1610 -2558);
PAINT MONO (-1610 -2558);
DISPLAY INVISIBLE (-1610 -2558);
FORCEPROP 2 LAST SIG_NAME OCP_V3_2_PRSNT2_R_N
J 0
(-2110 -2590);
DISPLAY 0.553191 (-2110 -2590);
PAINT WHITE (-2110 -2590);
DOT 1 (2132 -275);
DOT 1 (1050 2050);
DOT 1 (1050 2150);
DOT 1 (2125 1250);
DOT 1 (2375 1900);
DOT 1 (2600 -725);
DOT 1 (2550 -425);
DOT 1 (-2325 -2700);
DOT 1 (-2550 -2600);
DOT 1 (-2550 -2125);
DOT 1 (-2550 -1700);
DOT 1 (-2325 -1800);
DOT 1 (-2550 -1225);
DOT 1 (-2350 -1225);
DOT 1 (-2975 -675);
DOT 1 (-725 -2600);
DOT 1 (-725 -2300);
DOT 1 (-500 -2650);
DOT 1 (-725 -1800);
DOT 1 (-500 -1750);
DOT 1 (-750 -65);
DOT 1 (-175 -925);
DOT 1 (-175 -625);
DOT 1 (-175 -425);
DOT 1 (-4075 1000);
DOT 1 (-2825 1300);
DOT 1 (-2325 1675);
DOT 1 (-750 425);
DOT 1 (-525 425);
DOT 1 (-175 425);
DOT 1 (-50 1400);
DOT 1 (-50 1700);
DOT 1 (-50 1900);
DOT 1 (-400 2750);
DOT 1 (-50 2750);
DOT 1 (150 -2300);
DOT 1 (1675 -2150);
DOT 1 (1900 -2300);
DOT 1 (675 -1225);
DOT 1 (150 -525);
DOT 1 (925 -225);
DOT 1 (925 -275);
DOT 1 (925 -175);
DOT 1 (925 -75);
DOT 1 (925 -125);
DOT 1 (1675 -1675);
DOT 1 (1900 -1675);
DOT 1 (1950 -1075);
DOT 1 (2000 -1075);
DOT 1 (2250 -2475);
DOT 1 (2050 -1075);
DOT 1 (2150 -1075);
DOT 1 (2275 -725);
DOT 1 (2250 -425);
DOT 1 (2132 -225);
DOT 1 (2132 -175);
DOT 1 (2132 -125);
DOT 1 (2132 -75);
DOT 1 (3675 -525);
DOT 1 (150 0);
DOT 1 (150 425);
DOT 1 (925 -25);
DOT 1 (275 1800);
DOT 1 (800 1100);
DOT 1 (275 2325);
DOT 1 (275 2750);
DOT 1 (1050 2100);
DOT 1 (1050 2250);
DOT 1 (1050 2200);
DOT 1 (1050 2300);
DOT 1 (2132 -25);
DOT 1 (2250 -25);
DOT 1 (2345 -25);
DOT 1 (2650 600);
DOT 1 (2075 1250);
DOT 1 (2175 1250);
DOT 1 (2275 1250);
DOT 1 (2650 1900);
DOT 1 (3125 225);
DOT 1 (3450 -25);
DOT 1 (3550 225);
DOT 1 (3125 600);
DOT 1 (3550 600);
DOT 1 (3950 225);
DOT 1 (3950 600);
DOT 1 (3800 1800);
DOT 1 (2257 2050);
DOT 1 (2257 2100);
DOT 1 (2257 2150);
DOT 1 (2257 2200);
DOT 1 (2257 2250);
DOT 1 (2257 2300);
DOT 1 (2375 2300);
DOT 1 (2470 2300);
DOT 1 (2775 2925);
DOT 1 (3275 2550);
DOT 1 (3275 2925);
DOT 1 (3600 2325);
DOT 1 (3850 2550);
DOT 1 (3850 2925);
FORCENOTE
VIMON(MAX)= 1.594V @ IOUT=1.6A
(1000 900) 0;
DISPLAY LEFT (1000 900);
DISPLAY 1.021277 (1000 900);
PAINT WHITE (1000 900);
FORCENOTE
VIMON(MAX)= 1.679V @ IOUT=9.03A
(1000 -1425) 0;
DISPLAY LEFT (1000 -1425);
DISPLAY 1.021277 (1000 -1425);
PAINT WHITE (1000 -1425);
FORCENOTE
20211130 CHANGE TO 1K OHM
(-4275 -2300) 0;
DISPLAY LEFT (-4275 -2300);
DISPLAY 1.276596 (-4275 -2300);
PAINT PINK (-4275 -2300);
FORCENOTE
20211130 CHANGE TO 1K OHM
(-4275 -1450) 0;
DISPLAY LEFT (-4275 -1450);
DISPLAY 1.276596 (-4275 -1450);
PAINT PINK (-4275 -1450);
FORCENOTE
UVP: 10.17V
(-750 -675) 0;
DISPLAY LEFT (-750 -675);
DISPLAY 1.021277 (-750 -675);
PAINT WHITE (-750 -675);
FORCENOTE
OVP: 14.91V
(-750 -750) 0;
DISPLAY LEFT (-750 -750);
DISPLAY 1.021277 (-750 -750);
PAINT WHITE (-750 -750);
FORCENOTE
OCP=IMAX*1.3=1.43A
(-4225 2700) 0;
DISPLAY LEFT (-4225 2700);
DISPLAY 0.936170 (-4225 2700);
FORCENOTE
IMAX=6.6A
(-4225 2375) 0;
DISPLAY LEFT (-4225 2375);
DISPLAY 1.021277 (-4225 2375);
FORCENOTE
OCP=IMAX*1.3=8.58A
(-4225 2300) 0;
DISPLAY LEFT (-4225 2300);
DISPLAY 1.021277 (-4225 2300);
FORCENOTE
P12V_OCP_V3_2
(-4225 2450) 0;
DISPLAY LEFT (-4225 2450);
DISPLAY 1.021277 (-4225 2450);
FORCENOTE
P3V3_OCP_V3_2_R
(-4225 2850) 0;
DISPLAY LEFT (-4225 2850);
DISPLAY 0.936170 (-4225 2850);
FORCENOTE
IMAX=1.1A
(-4225 2775) 0;
DISPLAY LEFT (-4225 2775);
DISPLAY 0.936170 (-4225 2775);
FORCENOTE
DESIGN SPECIFICATION
(-4268 2952) 0;
DISPLAY LEFT (-4268 2952);
DISPLAY 1.170213 (-4268 2952);
FORCENOTE
OVP: 3.89V
(-575 1525) 0;
DISPLAY LEFT (-575 1525);
DISPLAY 1.021277 (-575 1525);
PAINT WHITE (-575 1525);
FORCENOTE
UVP: 2.63V
(-575 1600) 0;
DISPLAY LEFT (-575 1600);
DISPLAY 1.021277 (-575 1600);
PAINT WHITE (-575 1600);
FORCENOTE
20211108 MODIFY FOR GT
(-1625 3125) 0;
DISPLAY LEFT (-1625 3125);
DISPLAY 2.510638 (-1625 3125);
PAINT PINK (-1625 3125);
FORCENOTE
START UP TIME:8.21MS
(3325 -650) 0;
DISPLAY LEFT (3325 -650);
DISPLAY 1.021277 (3325 -650);
PAINT WHITE (3325 -650);
FORCENOTE
START UP TIME:3.94MS
(2850 1500) 0;
DISPLAY LEFT (2850 1500);
DISPLAY 1.021277 (2850 1500);
PAINT WHITE (2850 1500);
QUIT
